G04 ================== begin FILE IDENTIFICATION RECORD ==================*
G04 Layout Name:  15750-1.brd*
G04 Film Name:    L1*
G04 File Format:  Gerber RS274X*
G04 File Origin:  Cadence Allegro 16.5-S056*
G04 Origin Date:  Fri Dec 30 13:21:35 2016*
G04 *
G04 Layer:  VIA CLASS/TOP*
G04 Layer:  PIN/TOP*
G04 Layer:  ETCH/TOP*
G04 Layer:  DRAWING FORMAT/LAYER_PCB_STORY*
G04 Layer:  DRAWING FORMAT/LAYER_L1*
G04 *
G04 Offset:    (0.00 0.00)*
G04 Mirror:    No*
G04 Mode:      Positive*
G04 Rotation:  0*
G04 FullContactRelief:  No*
G04 UndefLineWidth:     6.00*
G04 ================== end FILE IDENTIFICATION RECORD ====================*
%FSLAX35Y35*MOIN*%
%IR0*IPPOS*OFA0.00000B0.00000*MIA0B0*SFA1.00000B1.00000*%
%AMMACRO48*
4,1,40,.013,.017,
-.013,.017,
-.013695,.016939,
-.014368,.016759,
-.015,.016464,
-.015571,.016064,
-.016064,.015571,
-.016464,.015,
-.016759,.014368,
-.016939,.013695,
-.017,.013,
-.017,-.013,
-.016939,-.013695,
-.016759,-.014368,
-.016464,-.015,
-.016064,-.015571,
-.015571,-.016064,
-.015,-.016464,
-.014368,-.016759,
-.013695,-.016939,
-.013,-.017,
.013,-.017,
.013695,-.016939,
.014368,-.016759,
.015,-.016464,
.015571,-.016064,
.016064,-.015571,
.016464,-.015,
.016759,-.014368,
.016939,-.013695,
.017,-.013,
.017,.013,
.016939,.013695,
.016759,.014368,
.016464,.015,
.016064,.015571,
.015571,.016064,
.015,.016464,
.014368,.016759,
.013695,.016939,
.013,.017,
0.0*
%
%ADD48MACRO48*%
%AMMACRO26*
4,1,40,.017,-.013,
.017,.013,
.016939,.013695,
.016759,.014368,
.016464,.015,
.016064,.015571,
.015571,.016064,
.015,.016464,
.014368,.016759,
.013695,.016939,
.013,.017,
-.013,.017,
-.013695,.016939,
-.014368,.016759,
-.015,.016464,
-.015571,.016064,
-.016064,.015571,
-.016464,.015,
-.016759,.014368,
-.016939,.013695,
-.017,.013,
-.017,-.013,
-.016939,-.013695,
-.016759,-.014368,
-.016464,-.015,
-.016064,-.015571,
-.015571,-.016064,
-.015,-.016464,
-.014368,-.016759,
-.013695,-.016939,
-.013,-.017,
.013,-.017,
.013695,-.016939,
.014368,-.016759,
.015,-.016464,
.015571,-.016064,
.016064,-.015571,
.016464,-.015,
.016759,-.014368,
.016939,-.013695,
.017,-.013,
0.0*
%
%ADD26MACRO26*%
%ADD46R,.102X.053*%
%ADD10C,.01*%
%ADD31C,.02*%
%ADD14C,.022*%
%ADD13C,.04*%
%ADD52R,.108X.047*%
%ADD16C,.028*%
%ADD56C,.056*%
%AMMACRO42*
4,1,40,.011,-.007,
.011,.007,
.010939,.007695,
.010759,.008368,
.010464,.009,
.010064,.009571,
.009571,.010064,
.009,.010464,
.008368,.010759,
.007695,.010939,
.007,.011,
-.007,.011,
-.007695,.010939,
-.008368,.010759,
-.009,.010464,
-.009571,.010064,
-.010064,.009571,
-.010464,.009,
-.010759,.008368,
-.010939,.007695,
-.011,.007,
-.011,-.007,
-.010939,-.007695,
-.010759,-.008368,
-.010464,-.009,
-.010064,-.009571,
-.009571,-.010064,
-.009,-.010464,
-.008368,-.010759,
-.007695,-.010939,
-.007,-.011,
.007,-.011,
.007695,-.010939,
.008368,-.010759,
.009,-.010464,
.009571,-.010064,
.010064,-.009571,
.010464,-.009,
.010759,-.008368,
.010939,-.007695,
.011,-.007,
0.0*
%
%ADD42MACRO42*%
%AMMACRO18*
4,1,40,.007,.011,
-.007,.011,
-.007695,.010939,
-.008368,.010759,
-.009,.010464,
-.009571,.010064,
-.010064,.009571,
-.010464,.009,
-.010759,.008368,
-.010939,.007695,
-.011,.007,
-.011,-.007,
-.010939,-.007695,
-.010759,-.008368,
-.010464,-.009,
-.010064,-.009571,
-.009571,-.010064,
-.009,-.010464,
-.008368,-.010759,
-.007695,-.010939,
-.007,-.011,
.007,-.011,
.007695,-.010939,
.008368,-.010759,
.009,-.010464,
.009571,-.010064,
.010064,-.009571,
.010464,-.009,
.010759,-.008368,
.010939,-.007695,
.011,-.007,
.011,.007,
.010939,.007695,
.010759,.008368,
.010464,.009,
.010064,.009571,
.009571,.010064,
.009,.010464,
.008368,.010759,
.007695,.010939,
.007,.011,
0.0*
%
%ADD18MACRO18*%
%AMMACRO34*
4,1,40,-.012,.008,
-.012,-.008,
-.011939,-.008695,
-.011759,-.009368,
-.011464,-.01,
-.011064,-.010571,
-.010571,-.011064,
-.01,-.011464,
-.009368,-.011759,
-.008695,-.011939,
-.008,-.012,
.008,-.012,
.008695,-.011939,
.009368,-.011759,
.01,-.011464,
.010571,-.011064,
.011064,-.010571,
.011464,-.01,
.011759,-.009368,
.011939,-.008695,
.012,-.008,
.012,.008,
.011939,.008695,
.011759,.009368,
.011464,.01,
.011064,.010571,
.010571,.011064,
.01,.011464,
.009368,.011759,
.008695,.011939,
.008,.012,
-.008,.012,
-.008695,.011939,
-.009368,.011759,
-.01,.011464,
-.010571,.011064,
-.011064,.010571,
-.011464,.01,
-.011759,.009368,
-.011939,.008695,
-.012,.008,
0.0*
%
%ADD34MACRO34*%
%AMMACRO24*
4,1,20,-.049,-.034,
-.049,-.0155,
-.074,-.0155,
-.074,-.0045,
-.049,-.0045,
-.049,.0045,
-.074,.0045,
-.074,.0155,
-.049,.0155,
-.049,.034,
.049,.034,
.049,.0155,
.074,.0155,
.074,.0045,
.049,.0045,
.049,-.0045,
.074,-.0045,
.074,-.0155,
.049,-.0155,
.049,-.034,
-.049,-.034,
0.0*
%
%ADD24MACRO24*%
%AMMACRO23*
4,1,40,.008,.012,
-.008,.012,
-.008695,.011939,
-.009368,.011759,
-.01,.011464,
-.010571,.011064,
-.011064,.010571,
-.011464,.01,
-.011759,.009368,
-.011939,.008695,
-.012,.008,
-.012,-.008,
-.011939,-.008695,
-.011759,-.009368,
-.011464,-.01,
-.011064,-.010571,
-.010571,-.011064,
-.01,-.011464,
-.009368,-.011759,
-.008695,-.011939,
-.008,-.012,
.008,-.012,
.008695,-.011939,
.009368,-.011759,
.01,-.011464,
.010571,-.011064,
.011064,-.010571,
.011464,-.01,
.011759,-.009368,
.011939,-.008695,
.012,-.008,
.012,.008,
.011939,.008695,
.011759,.009368,
.011464,.01,
.011064,.010571,
.010571,.011064,
.01,.011464,
.009368,.011759,
.008695,.011939,
.008,.012,
0.0*
%
%ADD23MACRO23*%
%AMMACRO53*
4,1,40,-.017,.013,
-.017,-.013,
-.016939,-.013695,
-.016759,-.014368,
-.016464,-.015,
-.016064,-.015571,
-.015571,-.016064,
-.015,-.016464,
-.014368,-.016759,
-.013695,-.016939,
-.013,-.017,
.013,-.017,
.013695,-.016939,
.014368,-.016759,
.015,-.016464,
.015571,-.016064,
.016064,-.015571,
.016464,-.015,
.016759,-.014368,
.016939,-.013695,
.017,-.013,
.017,.013,
.016939,.013695,
.016759,.014368,
.016464,.015,
.016064,.015571,
.015571,.016064,
.015,.016464,
.014368,.016759,
.013695,.016939,
.013,.017,
-.013,.017,
-.013695,.016939,
-.014368,.016759,
-.015,.016464,
-.015571,.016064,
-.016064,.015571,
-.016464,.015,
-.016759,.014368,
-.016939,.013695,
-.017,.013,
0.0*
%
%ADD53MACRO53*%
%AMMACRO44*
4,1,6,.005,.0135,
.005,.0065,
.025,-.0135,
-.025,-.0135,
-.005,.0065,
-.005,.0135,
.005,.0135,
0.0*
%
%ADD44MACRO44*%
%AMMACRO43*
4,1,40,.011,-.007,
.011,.007,
.010939,.007695,
.010759,.008368,
.010464,.009,
.010064,.009571,
.009571,.010064,
.009,.010464,
.008368,.010759,
.007695,.010939,
.007,.011,
-.007,.011,
-.007695,.010939,
-.008368,.010759,
-.009,.010464,
-.009571,.010064,
-.010064,.009571,
-.010464,.009,
-.010759,.008368,
-.010939,.007695,
-.011,.007,
-.011,-.007,
-.010939,-.007695,
-.010759,-.008368,
-.010464,-.009,
-.010064,-.009571,
-.009571,-.010064,
-.009,-.010464,
-.008368,-.010759,
-.007695,-.010939,
-.007,-.011,
.007,-.011,
.007695,-.010939,
.008368,-.010759,
.009,-.010464,
.009571,-.010064,
.010064,-.009571,
.010464,-.009,
.010759,-.008368,
.010939,-.007695,
.011,-.007,
0.0*
%
%ADD43MACRO43*%
%AMMACRO19*
4,1,40,.007,.011,
-.007,.011,
-.007695,.010939,
-.008368,.010759,
-.009,.010464,
-.009571,.010064,
-.010064,.009571,
-.010464,.009,
-.010759,.008368,
-.010939,.007695,
-.011,.007,
-.011,-.007,
-.010939,-.007695,
-.010759,-.008368,
-.010464,-.009,
-.010064,-.009571,
-.009571,-.010064,
-.009,-.010464,
-.008368,-.010759,
-.007695,-.010939,
-.007,-.011,
.007,-.011,
.007695,-.010939,
.008368,-.010759,
.009,-.010464,
.009571,-.010064,
.010064,-.009571,
.010464,-.009,
.010759,-.008368,
.010939,-.007695,
.011,-.007,
.011,.007,
.010939,.007695,
.010759,.008368,
.010464,.009,
.010064,.009571,
.009571,.010064,
.009,.010464,
.008368,.010759,
.007695,.010939,
.007,.011,
0.0*
%
%ADD19MACRO19*%
%AMMACRO33*
4,1,40,-.012,.008,
-.012,-.008,
-.011939,-.008695,
-.011759,-.009368,
-.011464,-.01,
-.011064,-.010571,
-.010571,-.011064,
-.01,-.011464,
-.009368,-.011759,
-.008695,-.011939,
-.008,-.012,
.008,-.012,
.008695,-.011939,
.009368,-.011759,
.01,-.011464,
.010571,-.011064,
.011064,-.010571,
.011464,-.01,
.011759,-.009368,
.011939,-.008695,
.012,-.008,
.012,.008,
.011939,.008695,
.011759,.009368,
.011464,.01,
.011064,.010571,
.010571,.011064,
.01,.011464,
.009368,.011759,
.008695,.011939,
.008,.012,
-.008,.012,
-.008695,.011939,
-.009368,.011759,
-.01,.011464,
-.010571,.011064,
-.011064,.010571,
-.011464,.01,
-.011759,.009368,
-.011939,.008695,
-.012,.008,
0.0*
%
%ADD33MACRO33*%
%AMMACRO22*
4,1,40,.008,.012,
-.008,.012,
-.008695,.011939,
-.009368,.011759,
-.01,.011464,
-.010571,.011064,
-.011064,.010571,
-.011464,.01,
-.011759,.009368,
-.011939,.008695,
-.012,.008,
-.012,-.008,
-.011939,-.008695,
-.011759,-.009368,
-.011464,-.01,
-.011064,-.010571,
-.010571,-.011064,
-.01,-.011464,
-.009368,-.011759,
-.008695,-.011939,
-.008,-.012,
.008,-.012,
.008695,-.011939,
.009368,-.011759,
.01,-.011464,
.010571,-.011064,
.011064,-.010571,
.011464,-.01,
.011759,-.009368,
.011939,-.008695,
.012,-.008,
.012,.008,
.011939,.008695,
.011759,.009368,
.011464,.01,
.011064,.010571,
.010571,.011064,
.01,.011464,
.009368,.011759,
.008695,.011939,
.008,.012,
0.0*
%
%ADD22MACRO22*%
%AMMACRO54*
4,1,40,-.017,.013,
-.017,-.013,
-.016939,-.013695,
-.016759,-.014368,
-.016464,-.015,
-.016064,-.015571,
-.015571,-.016064,
-.015,-.016464,
-.014368,-.016759,
-.013695,-.016939,
-.013,-.017,
.013,-.017,
.013695,-.016939,
.014368,-.016759,
.015,-.016464,
.015571,-.016064,
.016064,-.015571,
.016464,-.015,
.016759,-.014368,
.016939,-.013695,
.017,-.013,
.017,.013,
.016939,.013695,
.016759,.014368,
.016464,.015,
.016064,.015571,
.015571,.016064,
.015,.016464,
.014368,.016759,
.013695,.016939,
.013,.017,
-.013,.017,
-.013695,.016939,
-.014368,.016759,
-.015,.016464,
-.015571,.016064,
-.016064,.015571,
-.016464,.015,
-.016759,.014368,
-.016939,.013695,
-.017,.013,
0.0*
%
%ADD54MACRO54*%
%ADD37R,.06X.012*%
%ADD50R,.061X.012*%
%ADD32R,.012X.06*%
%ADD49R,.06X.014*%
%ADD41R,.044X.012*%
%ADD38R,.014X.06*%
%ADD20R,.012X.036*%
%ADD12C,.315*%
%ADD17R,.045X.055*%
%ADD55R,.016X.048*%
%ADD39R,.055X.045*%
%ADD51R,.095X.09*%
%ADD11R,.272X.272*%
%AMMACRO35*
4,1,40,-.007,-.011,
.007,-.011,
.007695,-.010939,
.008368,-.010759,
.009,-.010464,
.009571,-.010064,
.010064,-.009571,
.010464,-.009,
.010759,-.008368,
.010939,-.007695,
.011,-.007,
.011,.007,
.010939,.007695,
.010759,.008368,
.010464,.009,
.010064,.009571,
.009571,.010064,
.009,.010464,
.008368,.010759,
.007695,.010939,
.007,.011,
-.007,.011,
-.007695,.010939,
-.008368,.010759,
-.009,.010464,
-.009571,.010064,
-.010064,.009571,
-.010464,.009,
-.010759,.008368,
-.010939,.007695,
-.011,.007,
-.011,-.007,
-.010939,-.007695,
-.010759,-.008368,
-.010464,-.009,
-.010064,-.009571,
-.009571,-.010064,
-.009,-.010464,
-.008368,-.010759,
-.007695,-.010939,
-.007,-.011,
0.0*
%
%ADD35MACRO35*%
%AMMACRO30*
4,1,40,-.008,-.012,
.008,-.012,
.008695,-.011939,
.009368,-.011759,
.01,-.011464,
.010571,-.011064,
.011064,-.010571,
.011464,-.01,
.011759,-.009368,
.011939,-.008695,
.012,-.008,
.012,.008,
.011939,.008695,
.011759,.009368,
.011464,.01,
.011064,.010571,
.010571,.011064,
.01,.011464,
.009368,.011759,
.008695,.011939,
.008,.012,
-.008,.012,
-.008695,.011939,
-.009368,.011759,
-.01,.011464,
-.010571,.011064,
-.011064,.010571,
-.011464,.01,
-.011759,.009368,
-.011939,.008695,
-.012,.008,
-.012,-.008,
-.011939,-.008695,
-.011759,-.009368,
-.011464,-.01,
-.011064,-.010571,
-.010571,-.011064,
-.01,-.011464,
-.009368,-.011759,
-.008695,-.011939,
-.008,-.012,
0.0*
%
%ADD30MACRO30*%
%AMMACRO15*
4,1,40,.012,-.008,
.012,.008,
.011939,.008695,
.011759,.009368,
.011464,.01,
.011064,.010571,
.010571,.011064,
.01,.011464,
.009368,.011759,
.008695,.011939,
.008,.012,
-.008,.012,
-.008695,.011939,
-.009368,.011759,
-.01,.011464,
-.010571,.011064,
-.011064,.010571,
-.011464,.01,
-.011759,.009368,
-.011939,.008695,
-.012,.008,
-.012,-.008,
-.011939,-.008695,
-.011759,-.009368,
-.011464,-.01,
-.011064,-.010571,
-.010571,-.011064,
-.01,-.011464,
-.009368,-.011759,
-.008695,-.011939,
-.008,-.012,
.008,-.012,
.008695,-.011939,
.009368,-.011759,
.01,-.011464,
.010571,-.011064,
.011064,-.010571,
.011464,-.01,
.011759,-.009368,
.011939,-.008695,
.012,-.008,
0.0*
%
%ADD15MACRO15*%
%AMMACRO27*
4,1,40,-.011,.007,
-.011,-.007,
-.010939,-.007695,
-.010759,-.008368,
-.010464,-.009,
-.010064,-.009571,
-.009571,-.010064,
-.009,-.010464,
-.008368,-.010759,
-.007695,-.010939,
-.007,-.011,
.007,-.011,
.007695,-.010939,
.008368,-.010759,
.009,-.010464,
.009571,-.010064,
.010064,-.009571,
.010464,-.009,
.010759,-.008368,
.010939,-.007695,
.011,-.007,
.011,.007,
.010939,.007695,
.010759,.008368,
.010464,.009,
.010064,.009571,
.009571,.010064,
.009,.010464,
.008368,.010759,
.007695,.010939,
.007,.011,
-.007,.011,
-.007695,.010939,
-.008368,.010759,
-.009,.010464,
-.009571,.010064,
-.010064,.009571,
-.010464,.009,
-.010759,.008368,
-.010939,.007695,
-.011,.007,
0.0*
%
%ADD27MACRO27*%
%AMMACRO47*
4,1,40,.013,.017,
-.013,.017,
-.013695,.016939,
-.014368,.016759,
-.015,.016464,
-.015571,.016064,
-.016064,.015571,
-.016464,.015,
-.016759,.014368,
-.016939,.013695,
-.017,.013,
-.017,-.013,
-.016939,-.013695,
-.016759,-.014368,
-.016464,-.015,
-.016064,-.015571,
-.015571,-.016064,
-.015,-.016464,
-.014368,-.016759,
-.013695,-.016939,
-.013,-.017,
.013,-.017,
.013695,-.016939,
.014368,-.016759,
.015,-.016464,
.015571,-.016064,
.016064,-.015571,
.016464,-.015,
.016759,-.014368,
.016939,-.013695,
.017,-.013,
.017,.013,
.016939,.013695,
.016759,.014368,
.016464,.015,
.016064,.015571,
.015571,.016064,
.015,.016464,
.014368,.016759,
.013695,.016939,
.013,.017,
0.0*
%
%ADD47MACRO47*%
%AMMACRO45*
4,1,6,.025,.0135,
.005,-.0065,
.005,-.0135,
-.005,-.0135,
-.005,-.0065,
-.025,.0135,
.025,.0135,
0.0*
%
%ADD45MACRO45*%
%AMMACRO25*
4,1,40,.017,-.013,
.017,.013,
.016939,.013695,
.016759,.014368,
.016464,.015,
.016064,.015571,
.015571,.016064,
.015,.016464,
.014368,.016759,
.013695,.016939,
.013,.017,
-.013,.017,
-.013695,.016939,
-.014368,.016759,
-.015,.016464,
-.015571,.016064,
-.016064,.015571,
-.016464,.015,
-.016759,.014368,
-.016939,.013695,
-.017,.013,
-.017,-.013,
-.016939,-.013695,
-.016759,-.014368,
-.016464,-.015,
-.016064,-.015571,
-.015571,-.016064,
-.015,-.016464,
-.014368,-.016759,
-.013695,-.016939,
-.013,-.017,
.013,-.017,
.013695,-.016939,
.014368,-.016759,
.015,-.016464,
.015571,-.016064,
.016064,-.015571,
.016464,-.015,
.016759,-.014368,
.016939,-.013695,
.017,-.013,
0.0*
%
%ADD25MACRO25*%
%AMMACRO40*
4,1,20,-.0655,.1095,
-.051,.1095,
-.051,.12,
-.0375,.12,
-.0375,.1095,
.0375,.1095,
.0375,.12,
.051,.12,
.051,.1095,
.0655,.1095,
.0655,-.1095,
.051,-.1095,
.051,-.12,
.0375,-.12,
.0375,-.1095,
-.0375,-.1095,
-.0375,-.12,
-.051,-.12,
-.051,-.1095,
-.0655,-.1095,
-.0655,.1095,
0.0*
%
%ADD40MACRO40*%
%AMMACRO36*
4,1,40,-.007,-.011,
.007,-.011,
.007695,-.010939,
.008368,-.010759,
.009,-.010464,
.009571,-.010064,
.010064,-.009571,
.010464,-.009,
.010759,-.008368,
.010939,-.007695,
.011,-.007,
.011,.007,
.010939,.007695,
.010759,.008368,
.010464,.009,
.010064,.009571,
.009571,.010064,
.009,.010464,
.008368,.010759,
.007695,.010939,
.007,.011,
-.007,.011,
-.007695,.010939,
-.008368,.010759,
-.009,.010464,
-.009571,.010064,
-.010064,.009571,
-.010464,.009,
-.010759,.008368,
-.010939,.007695,
-.011,.007,
-.011,-.007,
-.010939,-.007695,
-.010759,-.008368,
-.010464,-.009,
-.010064,-.009571,
-.009571,-.010064,
-.009,-.010464,
-.008368,-.010759,
-.007695,-.010939,
-.007,-.011,
0.0*
%
%ADD36MACRO36*%
%AMMACRO29*
4,1,40,-.008,-.012,
.008,-.012,
.008695,-.011939,
.009368,-.011759,
.01,-.011464,
.010571,-.011064,
.011064,-.010571,
.011464,-.01,
.011759,-.009368,
.011939,-.008695,
.012,-.008,
.012,.008,
.011939,.008695,
.011759,.009368,
.011464,.01,
.011064,.010571,
.010571,.011064,
.01,.011464,
.009368,.011759,
.008695,.011939,
.008,.012,
-.008,.012,
-.008695,.011939,
-.009368,.011759,
-.01,.011464,
-.010571,.011064,
-.011064,.010571,
-.011464,.01,
-.011759,.009368,
-.011939,.008695,
-.012,.008,
-.012,-.008,
-.011939,-.008695,
-.011759,-.009368,
-.011464,-.01,
-.011064,-.010571,
-.010571,-.011064,
-.01,-.011464,
-.009368,-.011759,
-.008695,-.011939,
-.008,-.012,
0.0*
%
%ADD29MACRO29*%
%AMMACRO21*
4,1,40,.012,-.008,
.012,.008,
.011939,.008695,
.011759,.009368,
.011464,.01,
.011064,.010571,
.010571,.011064,
.01,.011464,
.009368,.011759,
.008695,.011939,
.008,.012,
-.008,.012,
-.008695,.011939,
-.009368,.011759,
-.01,.011464,
-.010571,.011064,
-.011064,.010571,
-.011464,.01,
-.011759,.009368,
-.011939,.008695,
-.012,.008,
-.012,-.008,
-.011939,-.008695,
-.011759,-.009368,
-.011464,-.01,
-.011064,-.010571,
-.010571,-.011064,
-.01,-.011464,
-.009368,-.011759,
-.008695,-.011939,
-.008,-.012,
.008,-.012,
.008695,-.011939,
.009368,-.011759,
.01,-.011464,
.010571,-.011064,
.011064,-.010571,
.011464,-.01,
.011759,-.009368,
.011939,-.008695,
.012,-.008,
0.0*
%
%ADD21MACRO21*%
%AMMACRO28*
4,1,40,-.011,.007,
-.011,-.007,
-.010939,-.007695,
-.010759,-.008368,
-.010464,-.009,
-.010064,-.009571,
-.009571,-.010064,
-.009,-.010464,
-.008368,-.010759,
-.007695,-.010939,
-.007,-.011,
.007,-.011,
.007695,-.010939,
.008368,-.010759,
.009,-.010464,
.009571,-.010064,
.010064,-.009571,
.010464,-.009,
.010759,-.008368,
.010939,-.007695,
.011,-.007,
.011,.007,
.010939,.007695,
.010759,.008368,
.010464,.009,
.010064,.009571,
.009571,.010064,
.009,.010464,
.008368,.010759,
.007695,.010939,
.007,.011,
-.007,.011,
-.007695,.010939,
-.008368,.010759,
-.009,.010464,
-.009571,.010064,
-.010064,.009571,
-.010464,.009,
-.010759,.008368,
-.010939,.007695,
-.011,.007,
0.0*
%
%ADD28MACRO28*%
%ADD57C,.012*%
%ADD58C,.014*%
%ADD59C,.016*%
%ADD60C,.006*%
%ADD61C,.00538*%
%ADD62C,.00475*%
%ADD66C,.08004*%
%ADD63C,.09204*%
%ADD64C,.08704*%
%ADD67R,.01X.01*%
%ADD65C,.33904*%
G75*
%LPD*%
G75*
G36*
G01X223000Y2000D02*
X218000Y7000D01*
Y262000D01*
X212000Y268000D01*
X35802D01*
Y297302D01*
X6198D01*
Y269767D01*
G02X5516Y269484I-400J0D01*
G01X2000Y273000D01*
Y356000D01*
X7500Y361500D01*
X279404D01*
G02X279588Y360745I0J-400D01*
G03X295226I7819J-15041D01*
G02X295410Y361500I184J355D01*
G01X341500D01*
X347500Y355500D01*
Y279500D01*
X347000Y279000D01*
X338000D01*
X335500Y276500D01*
Y218000D01*
X338000Y215500D01*
X347000D01*
X347500Y215000D01*
Y196500D01*
X347000Y196000D01*
X319500D01*
X317000Y193500D01*
Y178500D01*
X316500Y178000D01*
X310218D01*
X308500Y179718D01*
Y181393D01*
G02X309124Y181724I400J0D01*
G03Y189104I2490J3690D01*
G02X308500Y189435I-224J331D01*
G01Y192500D01*
X316500Y200500D01*
Y216500D01*
X313000Y220000D01*
X309000D01*
X308500Y220500D01*
Y238500D01*
X303481Y243519D01*
X303580Y243657D01*
G03X303000Y246907I-1869J1343D01*
G01Y250000D01*
X302000Y251000D01*
X299835D01*
G03X299762Y251050I-941J-1296D01*
G02X299781Y251735I216J337D01*
G03X295931Y253584I-1281J2265D01*
G01X295948Y253483D01*
X293721Y251257D01*
X293671Y251243D01*
G03X293165Y251000I430J-1543D01*
G01X276500D01*
X274414Y253086D01*
Y267785D01*
X285643Y279014D01*
X297443D01*
X301714Y283285D01*
Y286100D01*
G02X302104Y286499I400J-1D01*
G03X300309Y294127I-104J4001D01*
G02X299740Y294489I-169J362D01*
G01Y296204D01*
X300376Y296840D01*
X300499Y296790D01*
G03X298290Y298999I1501J3710D01*
G01X298340Y298876D01*
X296860Y297396D01*
Y285296D01*
X295432Y283868D01*
X283632D01*
X269560Y269795D01*
Y258905D01*
G02X268878Y258622I-400J0D01*
G01X268500Y259000D01*
X235000D01*
X234500Y258500D01*
Y173500D01*
X230940Y169940D01*
X230814D01*
X228970Y168096D01*
Y167970D01*
X226000Y165000D01*
Y151000D01*
X226500Y150500D01*
X233500D01*
X234500Y149500D01*
Y63500D01*
X239500Y58500D01*
X264000D01*
X265885Y60385D01*
X265957Y60391D01*
G03X269884Y64318I-406J4333D01*
G01X269890Y64390D01*
X278000Y72500D01*
X282068D01*
Y71780D01*
X290570D01*
Y72500D01*
X291000D01*
X291500Y72000D01*
Y59000D01*
X292000Y58500D01*
X296964D01*
X307002Y48462D01*
X312038D01*
X317000Y43500D01*
Y23000D01*
X319000Y21000D01*
X346500D01*
X347000Y20500D01*
Y2500D01*
X346500Y2000D01*
X245176D01*
G02X244988Y2753I0J400D01*
G03X229038I-7975J14959D01*
G02X228850Y2000I-188J-353D01*
G01X223000D01*
G37*
G36*
G01X236000Y139862D02*
Y143882D01*
G02X236462Y144277I400J0D01*
G03X238362Y144895I343J2175D01*
G01X238966Y145500D01*
X247638D01*
X247670Y145489D01*
G03X248200Y145398I532J1511D01*
G01X249800D01*
G03X250330Y145489I-2J1602D01*
G01X250362Y145500D01*
X259000D01*
X259500Y145000D01*
Y136892D01*
X252842D01*
Y130351D01*
X255979D01*
X256017Y130334D01*
G03X256594Y130214I575J1319D01*
G01X259500D01*
Y123112D01*
X252842D01*
Y121644D01*
X252342D01*
Y102292D01*
X252842D01*
Y98022D01*
X252342D01*
Y82607D01*
X256360D01*
X259069Y79898D01*
X259500D01*
Y75868D01*
X252842D01*
Y73264D01*
X259500D01*
Y65838D01*
X259000Y65338D01*
X236662D01*
X236080Y65920D01*
X236091Y66016D01*
G03X236102Y66200I-1591J187D01*
G01Y67800D01*
G03X236011Y68330I-1602J-2D01*
G01X236000Y68362D01*
Y69638D01*
X236011Y69670D01*
G03X236102Y70200I-1511J532D01*
G01Y71800D01*
G03X236011Y72330I-1602J-2D01*
G01X236000Y72362D01*
Y73638D01*
X236011Y73670D01*
G03X236102Y74200I-1511J532D01*
G01Y75800D01*
G03X236011Y76330I-1602J-2D01*
G01X236000Y76362D01*
Y120638D01*
X236011Y120670D01*
G03X236102Y121200I-1511J532D01*
G01Y122800D01*
G03X236011Y123330I-1602J-2D01*
G01X236000Y123362D01*
Y124638D01*
X236011Y124670D01*
G03X236102Y125200I-1511J532D01*
G01Y126800D01*
G03X236011Y127330I-1602J-2D01*
G01X236000Y127362D01*
Y128638D01*
X236011Y128670D01*
G03X236102Y129200I-1511J532D01*
G01Y130800D01*
G03X236011Y131330I-1602J-2D01*
G01X236000Y131362D01*
Y133138D01*
X236011Y133170D01*
G03X236102Y133700I-1511J532D01*
G01Y135300D01*
G03X236011Y135830I-1602J-2D01*
G01X236000Y135862D01*
Y137138D01*
X236011Y137170D01*
G03X236102Y137700I-1511J532D01*
G01Y139300D01*
G03X236011Y139830I-1602J-2D01*
G01X236000Y139862D01*
G37*
G36*
G01X236500Y174000D02*
X236080Y174420D01*
X236091Y174516D01*
G03X236102Y174700I-1591J187D01*
G01Y176300D01*
G03X236011Y176830I-1602J-2D01*
G01X236000Y176862D01*
Y178138D01*
X236011Y178170D01*
G03X236102Y178700I-1511J532D01*
G01Y180300D01*
G03X236011Y180830I-1602J-2D01*
G01X236000Y180862D01*
Y182138D01*
X236011Y182170D01*
G03X236102Y182700I-1511J532D01*
G01Y184300D01*
G03X236011Y184830I-1602J-2D01*
G01X236000Y184862D01*
Y229138D01*
X236011Y229170D01*
G03X236102Y229700I-1511J532D01*
G01Y231300D01*
G03X236011Y231830I-1602J-2D01*
G01X236000Y231862D01*
Y233138D01*
X236011Y233170D01*
G03X236102Y233700I-1511J532D01*
G01Y235300D01*
G03X236011Y235830I-1602J-2D01*
G01X236000Y235862D01*
Y237138D01*
X236011Y237170D01*
G03X236102Y237700I-1511J532D01*
G01Y239300D01*
G03X236011Y239830I-1602J-2D01*
G01X236000Y239862D01*
Y241638D01*
X236011Y241670D01*
G03X236102Y242200I-1511J532D01*
G01Y243800D01*
G03X236011Y244330I-1602J-2D01*
G01X236000Y244362D01*
Y245638D01*
X236011Y245670D01*
G03X236102Y246200I-1511J532D01*
G01Y247800D01*
G03X236011Y248330I-1602J-2D01*
G01X236000Y248362D01*
Y253500D01*
X236500Y254000D01*
X247638D01*
X247670Y253989D01*
G03X248200Y253898I532J1511D01*
G01X249800D01*
G03X250330Y253989I-2J1602D01*
G01X250362Y254000D01*
X259000D01*
X259500Y253500D01*
Y245554D01*
X252842D01*
Y239013D01*
X255979D01*
X256017Y238996D01*
G03X256594Y238876I575J1319D01*
G01X259500D01*
Y231774D01*
X252842D01*
Y230306D01*
X252342D01*
Y210954D01*
X252842D01*
Y206684D01*
X252342D01*
Y191269D01*
X256360D01*
X259069Y188560D01*
X259500D01*
Y184530D01*
X252842D01*
Y181926D01*
X259500D01*
Y174500D01*
X259000Y174000D01*
X236500D01*
G37*
G36*
G01X281100Y175561D02*
X278900D01*
X278500Y175961D01*
Y180961D01*
X279000Y181461D01*
X281000D01*
X281500Y180961D01*
Y175961D01*
X281100Y175561D01*
G37*
%LPC*%
G75*
G36*
G01X121425Y274299D02*
X121338Y274302D01*
X116708Y269672D01*
X106704D01*
X105376Y271000D01*
X78000D01*
X50000Y299000D01*
Y343000D01*
X58500Y351500D01*
X131000D01*
X136000Y346500D01*
Y334500D01*
X136500Y334000D01*
X178500D01*
X180000Y332500D01*
Y307000D01*
X180500Y306500D01*
X191500D01*
X192000Y307000D01*
Y317301D01*
X191798Y317502D01*
Y332498D01*
X191998Y332698D01*
Y335500D01*
G02X192000Y335607I4002J-21D01*
G01Y338500D01*
X191500Y339000D01*
X185500D01*
X185000Y339500D01*
Y347000D01*
X186000Y348000D01*
X195500D01*
X196500Y347000D01*
X235500D01*
X236000Y346500D01*
Y335000D01*
X236500Y334500D01*
X258500D01*
X260000Y333000D01*
Y290000D01*
X259000Y289000D01*
X225112D01*
Y287762D01*
X225121Y287735D01*
G02X220701I-2210J-646D01*
G01X220710Y287762D01*
Y289000D01*
X206000D01*
X204000Y291000D01*
X163451D01*
G02X160011Y292914I-1140J2000D01*
G01X160008Y292992D01*
X152500Y300500D01*
Y303500D01*
X158000Y309000D01*
Y314500D01*
X157500Y315000D01*
X144500D01*
X144000Y314500D01*
Y310000D01*
X145000Y309000D01*
Y298500D01*
X139500Y293000D01*
X131362D01*
X131330Y292989D01*
G02X130800Y292898I-532J1511D01*
G01X129200D01*
G02X129016Y292909I3J1602D01*
G01X128920Y292920D01*
X128500Y292500D01*
Y290000D01*
X128278Y289777D01*
Y287242D01*
X128198Y287162D01*
X128201Y287075D01*
G02X125429Y284873I-2201J-75D01*
G03X124949Y284622I-104J-386D01*
G02X122084Y282931I-2450J878D01*
G01X121983Y282948D01*
X121346Y282310D01*
X121145D01*
G02X121033Y282113I-1445J691D01*
G01X121000Y282063D01*
Y281937D01*
X121033Y281887D01*
G02X121302Y281000I-1333J-888D01*
G01Y279600D01*
G02X121250Y279199I-1602J4D01*
G03X121616Y278699I387J-100D01*
G02X122753Y278311I-116J-2199D01*
G03X123291Y278388I227J329D01*
G02X125760Y279066I1709J-1388D01*
G03X126298Y279441I138J375D01*
G01Y282500D01*
G02X130702I2202J0D01*
G01Y279362D01*
X130862Y279202D01*
X214362D01*
X227702Y265862D01*
Y210362D01*
X230702Y207361D01*
Y202639D01*
X227202Y199138D01*
Y169500D01*
G02X224240Y167434I-2202J0D01*
G03X223702Y167059I-138J-375D01*
G01Y126412D01*
X232202Y117912D01*
Y97173D01*
X232210Y97146D01*
G02X227790I-2210J-646D01*
G01X227798Y97173D01*
Y116088D01*
X219298Y124588D01*
Y202412D01*
X221887Y205000D01*
X219798Y207088D01*
Y262588D01*
X211088Y271298D01*
X127588D01*
X123776Y275110D01*
G03X123187Y275085I-283J-282D01*
G02X121425Y274299I-1687J1415D01*
G37*
G36*
G01X301796Y44452D02*
G03X301204I-296J-269D01*
G02X297221Y46327I-1704J1548D01*
G03X296925Y46771I-396J57D01*
G02X295221Y49327I575J2229D01*
G03X294925Y49771I-396J57D01*
G02X297204Y53548I575J2229D01*
G03X297796I296J269D01*
G02X301779Y51673I1704J-1548D01*
G03X302075Y51229I396J-57D01*
G02X303779Y48673I-575J-2229D01*
G03X304075Y48229I396J-57D01*
G02X301796Y44452I-575J-2229D01*
G37*
G54D66*
X302000Y310500D03*
G54D63*
X22401Y341025D03*
X291000Y22500D03*
X316610Y341025D03*
G54D64*
X311614Y31870D03*
G54D67*
X232500Y65800D03*
Y68200D03*
Y69800D03*
Y72200D03*
Y73800D03*
Y76200D03*
Y120800D03*
Y123200D03*
Y124800D03*
Y127200D03*
Y128800D03*
Y131200D03*
Y133300D03*
Y135700D03*
Y137300D03*
Y139700D03*
Y174300D03*
Y176700D03*
Y178300D03*
Y180700D03*
Y182300D03*
Y184700D03*
Y229300D03*
Y231700D03*
Y233300D03*
Y235700D03*
Y237300D03*
Y239700D03*
Y241800D03*
Y244200D03*
Y245800D03*
Y248200D03*
X131200Y290500D03*
X167800Y338000D03*
X171200D03*
X238500Y68200D03*
Y69800D03*
Y72200D03*
Y73800D03*
Y76200D03*
Y120800D03*
Y123200D03*
Y124800D03*
Y127200D03*
Y128800D03*
Y131200D03*
Y133300D03*
Y135700D03*
Y137300D03*
Y139700D03*
X247800Y143000D03*
X250200D03*
X238500Y176700D03*
Y178300D03*
Y180700D03*
Y182300D03*
Y184700D03*
Y229300D03*
Y231700D03*
Y233300D03*
Y235700D03*
Y237300D03*
Y239700D03*
Y241800D03*
Y244200D03*
Y245800D03*
Y248200D03*
X247800Y251500D03*
X250200D03*
G54D65*
X25596Y316176D03*
%LPD*%
G75*
G36*
G01X69500Y303773D02*
X72502Y306774D01*
Y307088D01*
X72802D01*
Y311400D01*
X78789D01*
X79500Y310689D01*
Y283189D01*
X79000Y282689D01*
X70000D01*
X69500Y283189D01*
Y297427D01*
X69511Y297459D01*
G03X69602Y297989I-1511J532D01*
G01Y299389D01*
G03X69511Y299919I-1602J-2D01*
G01X69500Y299951D01*
Y303773D01*
G37*
G36*
G01X72802Y319900D02*
Y324290D01*
X72502D01*
Y326190D01*
X74500Y328189D01*
Y339000D01*
X73000Y340500D01*
Y343738D01*
X73011Y343770D01*
G03X73102Y344300I-1511J532D01*
G01Y345700D01*
G03X73011Y346230I-1602J-2D01*
G01X73000Y346262D01*
Y349000D01*
X73500Y349500D01*
X80500D01*
X81000Y349000D01*
Y335140D01*
X80848D01*
Y327238D01*
X81000D01*
Y320689D01*
X80211Y319900D01*
X72802D01*
G37*
G36*
G01X70752Y331689D02*
Y338189D01*
X73000D01*
X73298Y337890D01*
Y335140D01*
X73248D01*
Y331938D01*
X73000Y331689D01*
X70752D01*
G37*
G36*
G01X82000Y282000D02*
X81500Y282500D01*
Y304500D01*
X82000Y305000D01*
Y319990D01*
X82202Y320191D01*
Y334201D01*
X82500Y334500D01*
X90000D01*
X90500Y334000D01*
Y314462D01*
G03Y310538I1000J-1962D01*
G01Y309923D01*
X90483Y309884D01*
G03X90500Y308079I2017J-884D01*
G01Y299421D01*
G03Y297579I2000J-921D01*
G01Y295921D01*
G03Y294079I2000J-921D01*
G01Y282500D01*
X90000Y282000D01*
X82000D01*
G37*
G36*
G01X143000Y298500D02*
X133500D01*
X133000Y299000D01*
Y314500D01*
X133500Y315000D01*
X141500D01*
X142000Y314500D01*
Y310000D01*
X143048Y308951D01*
Y308748D01*
X143251D01*
X143500Y308500D01*
Y299000D01*
X143000Y298500D01*
G37*
G36*
G01X136500Y317500D02*
X136000Y318000D01*
Y332000D01*
X136500Y332500D01*
X178000D01*
X178500Y332000D01*
Y318000D01*
X178332Y317832D01*
X173266D01*
Y317632D01*
X168075D01*
X167942Y317500D01*
X136500D01*
G37*
G36*
G01X214500Y315000D02*
X212000Y317500D01*
X203063D01*
X203021Y317644D01*
G03X198665Y317832I-2210J-644D01*
G01X193168D01*
X193062Y317938D01*
Y330152D01*
X193000D01*
Y332000D01*
X193500Y332500D01*
X215000D01*
X215500Y332000D01*
Y317500D01*
X216000Y317000D01*
Y315500D01*
X215500Y315000D01*
X214500D01*
G37*
G36*
G01X257500Y292500D02*
X242000D01*
X226500Y308000D01*
Y326500D01*
X227000Y327000D01*
X257500D01*
X258000Y326500D01*
Y293000D01*
X257500Y292500D01*
G37*
%LPC*%
G75*
G54D67*
X71800Y297589D03*
Y299789D03*
X72000Y301489D03*
Y303889D03*
X75300Y343900D03*
Y346100D03*
X136250Y309950D03*
X141750Y322050D03*
X167800Y329000D03*
X171200D03*
%LPD*%
G75*
G54D10*
G01X58000Y320689D02*
X53500D01*
G01X66750Y289689D02*
Y294189D01*
G01D02*
X67250Y294689D01*
Y298689D01*
G01D02*
Y302689D01*
G01D02*
Y302939D01*
X71500Y307189D01*
Y309589D01*
G01X59000Y304189D02*
X59750Y303439D01*
X63000D01*
G01D02*
X66350Y306789D01*
X68580D01*
X69530Y307739D01*
Y309589D01*
G01X58000Y320689D02*
X59750Y322439D01*
Y325189D01*
G01D02*
X64165D01*
X67565Y321789D01*
G01X71500D02*
Y329439D01*
G01D02*
X70250D01*
X69050Y330639D01*
Y338139D01*
X68000Y339189D01*
G01D02*
Y342250D01*
X70750Y345000D01*
G01X162311Y293000D02*
Y298500D01*
G01X168311Y301750D02*
Y308000D01*
X169811Y309500D01*
G01X176168Y312594D02*
X172905D01*
X169811Y309500D01*
G01X176168Y310626D02*
X173922D01*
X172968Y309672D01*
Y306157D01*
X172311Y305500D01*
G01X162311Y298500D02*
X168061D01*
X168311Y298250D01*
G01X176168Y305500D02*
Y308657D01*
G01X176311Y301750D02*
Y305357D01*
X176168Y305500D01*
G01X204061Y304000D02*
X200811Y307250D01*
Y308000D01*
G01X195454Y310626D02*
X198185D01*
X200811Y308000D01*
G01X199811Y296250D02*
X203600D01*
G01D02*
X207500D01*
G01X199811Y299750D02*
X203600D01*
G01X195454Y308657D02*
Y304143D01*
X194811Y303500D01*
G01D02*
X195454Y302857D01*
Y299607D01*
X195561Y299500D01*
G01X199811Y299750D02*
X199561Y299500D01*
X195561D01*
G01X203600Y299750D02*
X206900D01*
X207350Y300200D01*
G01X195454Y316531D02*
X200342D01*
X200811Y317000D01*
G01X195454Y312594D02*
X199217D01*
X200811Y311000D01*
G01X218000Y292000D02*
X214000D01*
G01X208000D02*
Y295750D01*
X207500Y296250D01*
G01X210850Y300200D02*
X215611D01*
X215811Y300000D01*
G01X206943Y324000D02*
X217311D01*
X218311Y325000D01*
G01X232057Y324000D02*
X223311D01*
X222311Y325000D01*
X26087Y-114844D03*
X26435Y373984D03*
X175335Y62719D03*
Y189062D03*
X265551Y64724D03*
Y143464D03*
Y173386D03*
Y252126D03*
X311614Y31870D03*
Y185414D03*
X547104Y69007D03*
Y195351D03*
X696192Y373984D03*
G54D11*
X21000Y282500D03*
G54D20*
X67565Y309589D03*
X69530D03*
X71500D03*
Y321789D03*
X69530D03*
X67565D03*
X73470Y309589D03*
X75435D03*
Y321789D03*
X73470D03*
G54D21*
X70800Y302689D03*
X59800Y325189D03*
X210900Y300200D03*
X237300Y67000D03*
Y75000D03*
Y71000D03*
Y122000D03*
Y126000D03*
Y138500D03*
Y130000D03*
Y134500D03*
Y175500D03*
Y183500D03*
Y179500D03*
Y238500D03*
Y243000D03*
Y230500D03*
Y234500D03*
Y247000D03*
G54D30*
X71500Y332989D03*
X165000Y311800D03*
X249000Y147800D03*
Y256300D03*
G54D12*
X25596Y316176D03*
X237013Y17712D03*
X287407Y345704D03*
G54D40*
X185811Y318500D03*
G54D22*
X63000Y303489D03*
X103000Y284300D03*
X100500Y342489D03*
X109500Y286800D03*
X130000Y295300D03*
X203600Y299800D03*
X290000Y163300D03*
G54D13*
X22401Y341025D03*
X291000Y22500D03*
X316610Y341025D03*
G54D31*
G01X-176139Y-183003D02*
G02I-12000J0D01*
G01X-181289D02*
G02I-6850J0D01*
G01X-172139D02*
X-204139D01*
G01X-188139Y-199003D02*
Y-167003D01*
G01X-172139Y-199003D02*
Y-279003D01*
G01D02*
X1178561D01*
G01X-172139Y-234503D02*
X1178561D01*
G01X-172139Y-199003D02*
X1178561D01*
G01X8444Y316176D02*
X25596D01*
G01Y299024D02*
Y316176D01*
G01D02*
Y333328D01*
G01Y316176D02*
X42748D01*
G01X56250Y325189D02*
X52500D01*
G01X58200Y331189D02*
X52500D01*
G01X63250Y294189D02*
X59500D01*
G01X58000Y314689D02*
Y310689D01*
G01X63000Y299939D02*
X59500D01*
G01X74250Y346439D02*
X72689Y348000D01*
X69061D01*
X62000Y340939D01*
G01X58000Y337439D02*
X62000D01*
G01D02*
X65800Y333639D01*
Y331189D01*
G01X74250Y345000D02*
Y346439D01*
G01X103000Y280750D02*
Y277500D01*
G01X109500Y283250D02*
X108337D01*
X105837Y280750D01*
X103000D01*
G01X106137Y286000D02*
X104387Y284250D01*
X103000D01*
G01X103750Y310000D02*
Y313200D01*
G01X100250Y310000D02*
Y313200D01*
G01X96750Y325000D02*
Y328500D01*
G01Y321000D02*
Y325000D01*
G01Y317000D02*
Y321000D01*
G01X100500Y338939D02*
Y335689D01*
G01Y342439D02*
Y347289D01*
G01X109500Y286750D02*
X110250D01*
X112500Y289000D01*
G01X225000Y205000D02*
X222000Y208000D01*
Y263500D01*
X212000Y273500D01*
X128500D01*
X125000Y277000D01*
G01X225000Y169500D02*
Y200050D01*
X228501Y203551D01*
Y206449D01*
X225500Y209450D01*
Y264950D01*
X213450Y277000D01*
X129950D01*
X128500Y278450D01*
Y282500D01*
G01X130000Y295250D02*
Y298500D01*
G01X165000Y308250D02*
Y304189D01*
X164811Y304000D01*
G01X165000Y311750D02*
X162561D01*
X160811Y310000D01*
G01X176311Y298250D02*
Y294000D01*
G01X185811Y301600D02*
Y304200D01*
G01X192061Y299500D02*
X189961Y297400D01*
X185811D01*
G01D02*
X181411D01*
X181061Y297750D01*
G01X195811Y296000D02*
X194811D01*
X192061Y298750D01*
Y299500D01*
G01X196000Y335500D02*
Y331500D01*
G01X189500Y343800D02*
X193700D01*
X196000Y341500D01*
G01X219861Y17712D02*
X237013D01*
G01X230000Y96500D02*
Y117000D01*
X221500Y125500D01*
Y201500D01*
X225000Y205000D01*
G01X207561Y304000D02*
X219000D01*
X222911Y300089D01*
Y287089D01*
G01X237013Y17712D02*
Y34864D01*
G01Y17712D02*
X254165D01*
G01X249000Y147750D02*
X238103D01*
X236805Y146452D01*
G01X240200Y162300D02*
Y154674D01*
X238026Y152500D01*
X237000D01*
G01Y164250D02*
X238250D01*
X240200Y162300D01*
G01X258750Y168000D02*
X245900D01*
X240200Y162300D01*
G01X249000Y256250D02*
Y260000D01*
G01X268140Y161221D02*
X272919Y166000D01*
X279000D01*
G01X290500Y150750D02*
X278611D01*
X268140Y161221D01*
G01X270255Y345704D02*
X287407D01*
G01X283268Y144842D02*
X275768D01*
G01X278860Y162250D02*
X279000D01*
X281500Y159750D01*
X290000D01*
G01X283268Y172008D02*
X275500D01*
G01X279000Y166000D02*
X280200D01*
X282950Y163250D01*
X290000D01*
G01X287407Y328552D02*
Y345704D01*
G01D02*
X304559D01*
G01X300500Y129100D02*
X298900D01*
X296000Y132000D01*
Y132250D01*
G01X297000Y118000D02*
X294579D01*
X291500Y114921D01*
G01X297000Y124000D02*
X300000D01*
X301000Y125000D01*
G01X292000Y126000D02*
X294000Y124000D01*
X297000D01*
G01X294000Y150750D02*
X290500D01*
G01X298000D02*
X294000D01*
G01X294750Y245000D02*
Y244549D01*
X291500Y241299D01*
G01X302000Y306298D02*
Y310500D01*
G01D02*
Y314702D01*
G01X297798Y310500D02*
X302000D01*
G01D02*
X306202D01*
G01X391061Y-199003D02*
Y-279003D01*
G01X528561Y-199003D02*
Y-279003D01*
G01X643561Y-199003D02*
Y-279003D01*
G01X811061Y-199003D02*
Y-279003D01*
G01X981061Y-199003D02*
Y-279003D01*
G01X1178561Y-199003D02*
Y-279003D01*
G01X1210561Y-183003D02*
X1178561D01*
G01X1206561D02*
G02I-12000J0D01*
G01X1201411D02*
G02I-6850J0D01*
G01X1194561Y-199003D02*
Y-167003D01*
X103000Y277500D03*
X95000D03*
X99000D03*
X106500D03*
X92500Y295000D03*
X106137Y286000D03*
X100000Y288500D03*
X92500Y298500D03*
Y309000D03*
X107000Y311500D03*
Y308000D03*
X96750Y313250D03*
X103750Y313200D03*
X100250D03*
X103500Y317000D03*
Y321000D03*
X91500Y312500D03*
X100500Y335689D03*
X96750Y328500D03*
X100500Y347289D03*
X121500Y276500D03*
X118000D03*
X114500D03*
X110500Y277500D03*
X121456Y289154D03*
X122100Y280750D03*
X112500Y289000D03*
X108000Y295000D03*
X122000Y301000D03*
X108000Y298500D03*
X115000Y305000D03*
X119000D03*
X108000Y303100D03*
X120120Y315000D03*
X116500D03*
X109500Y334500D03*
X113000D03*
X117000D03*
X121000D03*
X125000Y277000D03*
X128500Y282500D03*
X126000Y287000D03*
X130000Y298500D03*
X124000Y315000D03*
X140500Y281000D03*
X215064Y316100D03*
X236805Y146452D03*
X225000Y160250D03*
Y149250D03*
X237000Y156000D03*
Y159780D03*
Y152500D03*
X225000Y164250D03*
X236500Y168500D03*
X225000Y169500D03*
X237000Y164250D03*
X251000Y88500D03*
X252000Y151500D03*
Y155000D03*
Y160500D03*
X251500Y164500D03*
X251000Y197000D03*
X263000Y96500D03*
Y88500D03*
Y81338D03*
Y84838D03*
X269650Y97899D03*
X271650Y109710D03*
X269650Y102299D03*
X263000Y104000D03*
X262819Y100157D03*
X271650Y114110D03*
X271250Y138750D03*
X267700Y153250D03*
X268140Y161221D03*
X258750Y168000D03*
X263000Y190000D03*
Y193500D03*
X269650Y210961D03*
Y206561D03*
X263000Y205000D03*
Y197000D03*
Y212500D03*
X262819Y208819D03*
X271650Y222772D03*
Y218372D03*
X263000Y240315D03*
X275100Y109710D03*
X273100Y102299D03*
Y97899D03*
X275100Y114110D03*
X278860Y162250D03*
X279000Y166000D03*
X273500Y194055D03*
Y199961D03*
X273100Y210961D03*
Y206561D03*
X275100Y222772D03*
Y218372D03*
X273600Y240250D03*
X295000Y86699D03*
Y89899D03*
X300500Y129100D03*
X301000Y125000D03*
X292000Y126000D03*
X299300Y137043D03*
Y132643D03*
X302800Y137043D03*
Y132643D03*
X290500Y154250D03*
X296500Y157500D03*
X302000D03*
X290500Y150750D03*
X291000Y169500D03*
X292000Y181500D03*
X294750Y195261D03*
X291300Y195361D03*
X294750Y198661D03*
X291300Y198561D03*
X325244Y49902D03*
Y53051D03*
Y56201D03*
Y62500D03*
Y59351D03*
Y75099D03*
Y65650D03*
Y78248D03*
Y68799D03*
Y71949D03*
Y93996D03*
Y84548D03*
Y97146D03*
Y87697D03*
Y90847D03*
Y81398D03*
Y112894D03*
Y103445D03*
Y106595D03*
Y109744D03*
Y100296D03*
Y128642D03*
Y119193D03*
Y144390D03*
Y138091D03*
Y153839D03*
Y156988D03*
Y160138D03*
Y150689D03*
Y147540D03*
Y163288D03*
Y166437D03*
Y169587D03*
G54D41*
X176168Y308657D03*
Y310626D03*
Y312594D03*
Y314563D03*
Y316531D03*
Y318500D03*
Y320469D03*
Y322437D03*
Y324406D03*
Y326374D03*
Y328343D03*
X195454Y310626D03*
Y308657D03*
Y326374D03*
Y324406D03*
Y322437D03*
Y320469D03*
Y318500D03*
Y316531D03*
Y314563D03*
Y312594D03*
Y328343D03*
G54D32*
X104955Y293900D03*
X102985D03*
X101015D03*
X99045D03*
Y303100D03*
X101015D03*
X102985D03*
X104955D03*
G54D50*
X256594Y68661D03*
Y70629D03*
Y72598D03*
Y74566D03*
Y84409D03*
Y86377D03*
Y88346D03*
Y90314D03*
Y92283D03*
Y94251D03*
Y96220D03*
Y98188D03*
Y100157D03*
Y102125D03*
Y104094D03*
Y106063D03*
Y108031D03*
Y110000D03*
Y111968D03*
Y113937D03*
Y115905D03*
Y117874D03*
Y119842D03*
Y121811D03*
Y123779D03*
Y125748D03*
Y127716D03*
Y129685D03*
Y131653D03*
Y133622D03*
Y135590D03*
Y137559D03*
Y139527D03*
Y177323D03*
Y179291D03*
Y181260D03*
Y183228D03*
Y193071D03*
Y195039D03*
Y197008D03*
Y198976D03*
Y200945D03*
Y202913D03*
Y204882D03*
Y206850D03*
Y208819D03*
Y210787D03*
Y212756D03*
Y214725D03*
Y216693D03*
Y218662D03*
Y220630D03*
Y222599D03*
Y224567D03*
Y226536D03*
Y228504D03*
Y230473D03*
Y232441D03*
Y234410D03*
Y236378D03*
Y238347D03*
Y240315D03*
Y242284D03*
Y244252D03*
Y246221D03*
Y248189D03*
X286319Y67677D03*
Y69645D03*
Y71614D03*
Y73582D03*
Y75551D03*
Y85393D03*
Y87362D03*
Y89330D03*
Y91299D03*
Y93267D03*
Y95236D03*
Y97204D03*
Y99173D03*
Y101141D03*
Y103110D03*
Y105078D03*
Y107047D03*
Y109015D03*
Y110984D03*
Y112952D03*
Y114921D03*
Y116889D03*
Y118858D03*
Y120826D03*
Y122795D03*
Y124763D03*
Y126732D03*
Y128700D03*
Y130669D03*
Y132637D03*
Y134606D03*
Y136574D03*
Y138543D03*
Y140511D03*
Y176339D03*
Y178307D03*
Y180276D03*
Y182244D03*
Y184213D03*
Y194055D03*
Y196024D03*
Y197992D03*
Y199961D03*
Y201929D03*
Y203898D03*
Y205866D03*
Y207835D03*
Y209803D03*
Y211772D03*
Y213740D03*
Y215709D03*
Y217677D03*
Y219646D03*
Y221614D03*
Y223583D03*
Y225551D03*
Y227520D03*
Y229488D03*
Y231457D03*
Y233425D03*
Y235394D03*
Y237362D03*
Y239331D03*
Y241299D03*
Y243268D03*
Y245236D03*
Y247205D03*
Y249173D03*
G54D23*
X63000Y299889D03*
X103000Y280700D03*
X100500Y338889D03*
X109500Y283200D03*
X130000Y291700D03*
X203600Y296200D03*
X290000Y159700D03*
G54D14*
X10000Y330000D03*
Y345000D03*
Y360000D03*
X40000Y270000D03*
Y285000D03*
Y300000D03*
Y330000D03*
Y345000D03*
X25000Y360000D03*
X40000D03*
X55000Y270000D03*
Y285000D03*
X52500Y325189D03*
Y331189D03*
X55000Y360000D03*
X70000Y270000D03*
X59500Y294189D03*
X72000Y286000D03*
Y290000D03*
X58000Y310689D03*
X64500Y309589D03*
X59500Y299939D03*
X71500Y315689D03*
X67900D03*
X72000Y336689D03*
X70000Y360000D03*
X85000Y270000D03*
X89000Y295189D03*
Y291189D03*
Y287189D03*
Y283189D03*
Y303689D03*
Y299689D03*
X75100Y315689D03*
X79000Y344000D03*
X89000Y329189D03*
Y333189D03*
X79000Y348000D03*
X85000Y360000D03*
X100000Y270000D03*
Y360000D03*
X115000D03*
X138500Y299500D03*
X134500Y307500D03*
X138500Y303500D03*
Y307500D03*
X137500Y324500D03*
X138000Y341500D03*
X130000Y360000D03*
X138000Y345500D03*
X142500Y299500D03*
Y303500D03*
Y307500D03*
X146500Y303500D03*
X150500D03*
X146500Y307500D03*
X150500D03*
X155000Y301350D03*
X141811Y324500D03*
X145811D03*
X153811D03*
X149811D03*
Y341500D03*
X141811D03*
X145811D03*
X153811D03*
X145000Y360000D03*
X149811Y345500D03*
X141811D03*
X145811D03*
X153811D03*
X162311Y293000D03*
X164811Y304000D03*
X160811Y310000D03*
X169811Y309500D03*
X172311Y305500D03*
X157811Y324500D03*
X161811D03*
X169811D03*
X165811D03*
X169811Y313500D03*
X165811Y341500D03*
X157811D03*
X161811D03*
X169811D03*
X160000Y360000D03*
X165811Y345500D03*
X169811D03*
X157811D03*
X161811D03*
X176311Y294000D03*
X185811Y304200D03*
Y310500D03*
X181811D03*
X181061Y297750D03*
X176168Y305500D03*
X181811Y318500D03*
X185811Y314500D03*
Y326500D03*
Y322500D03*
Y318500D03*
X181811Y326500D03*
Y322500D03*
Y314500D03*
X184500Y334000D03*
Y338000D03*
X175000Y360000D03*
X189811Y310500D03*
X195811Y296000D03*
X200811Y308000D03*
Y311000D03*
X189811Y318500D03*
Y322500D03*
Y326500D03*
Y314500D03*
X200811Y317000D03*
Y314000D03*
X190000Y360000D03*
X205000D03*
X218000Y292000D03*
X215811Y300000D03*
X222311Y325000D03*
X218311D03*
X220000Y360000D03*
X225000Y35000D03*
Y50000D03*
Y80000D03*
Y65000D03*
X230000Y75000D03*
Y67000D03*
Y71000D03*
X225000Y95000D03*
X230000Y96500D03*
X225000Y110000D03*
X230000Y126000D03*
Y130000D03*
Y122000D03*
Y138500D03*
Y142500D03*
Y134500D03*
Y175500D03*
Y179500D03*
Y183500D03*
X225000Y205000D03*
X230000Y243000D03*
Y234500D03*
Y238500D03*
Y230500D03*
Y247000D03*
Y251000D03*
X222911Y287089D03*
X237500Y340000D03*
Y344000D03*
Y336000D03*
X235000Y360000D03*
X255000Y5000D03*
Y35000D03*
X247000Y68838D03*
Y72838D03*
X251000Y68838D03*
Y72838D03*
X247000Y123838D03*
X251000D03*
X247000Y127838D03*
X251000D03*
X247000Y136338D03*
Y140838D03*
X251000D03*
Y136338D03*
Y177500D03*
X247000D03*
X251000Y181500D03*
X247000D03*
X251000Y245000D03*
X247000D03*
X251000Y236500D03*
X247000D03*
X251000Y232500D03*
X247000D03*
X251000Y249500D03*
X247000D03*
X249000Y260000D03*
X242500Y294000D03*
X246500D03*
X250500D03*
X242500Y306000D03*
Y302000D03*
Y298000D03*
X246500Y306000D03*
Y302000D03*
Y298000D03*
X250500D03*
Y302000D03*
Y306000D03*
X241500Y336000D03*
Y344000D03*
Y340000D03*
X250000Y360000D03*
X270000Y5000D03*
Y35000D03*
X262920Y131653D03*
X265000Y270000D03*
Y285000D03*
X271500Y294000D03*
X267500D03*
X271500Y306000D03*
Y302000D03*
Y298000D03*
X267500D03*
Y302000D03*
Y306000D03*
X260500Y340000D03*
Y344000D03*
Y336000D03*
X256500D03*
Y344000D03*
Y340000D03*
X265000Y360000D03*
X282500Y5000D03*
X272500Y20000D03*
X285000Y32500D03*
X275500Y63346D03*
X280000Y71614D03*
Y67677D03*
X273000Y92283D03*
X280169Y126732D03*
Y120826D03*
X275768Y144842D03*
X280169Y138543D03*
Y132637D03*
X280000Y176339D03*
X275500Y172008D03*
X280000Y180276D03*
X280169Y247205D03*
X275768Y253504D03*
X280000Y270000D03*
X275500Y294000D03*
X280000Y285000D03*
X275500Y298000D03*
Y302000D03*
Y306000D03*
X280000Y300000D03*
Y315000D03*
X295000Y5000D03*
X300000Y20000D03*
X299500Y46000D03*
X303500D03*
X300000Y35000D03*
X296500Y61000D03*
X300500D03*
X301500Y49000D03*
X297500D03*
X295500Y52000D03*
X299500D03*
X304565Y61142D03*
Y96142D03*
X304500Y92000D03*
X291500Y97204D03*
X291550Y91299D03*
X291500Y85393D03*
X295500Y110000D03*
Y100000D03*
X291500Y109960D03*
Y101960D03*
X295311Y127600D03*
X304500Y123820D03*
X291500Y114921D03*
X304565Y141142D03*
X295500Y208461D03*
X291500Y210961D03*
Y205866D03*
Y218461D03*
Y223583D03*
X301711Y245000D03*
X291500Y241299D03*
Y229488D03*
Y235394D03*
X295000Y270000D03*
Y285000D03*
Y300000D03*
Y315000D03*
X315000Y5000D03*
Y20000D03*
Y40000D03*
X313000Y179500D03*
X310000Y225000D03*
Y240000D03*
Y255000D03*
Y270000D03*
Y285000D03*
Y300000D03*
Y315000D03*
Y330000D03*
Y360000D03*
Y345000D03*
X324302Y203977D03*
X325000Y225000D03*
Y240000D03*
Y255000D03*
Y270000D03*
Y285000D03*
Y300000D03*
Y315000D03*
Y330000D03*
Y360000D03*
Y345000D03*
X345000Y5000D03*
Y20000D03*
X340000Y285000D03*
Y300000D03*
Y315000D03*
Y330000D03*
Y360000D03*
Y345000D03*
G54D60*
G01X-148956Y-251503D02*
Y-269003D01*
X-140222D01*
G01X-127089Y-257337D02*
Y-269003D01*
G01Y-252670D02*
X-127526Y-252378D01*
Y-251795D01*
X-127089Y-251503D01*
X-126652Y-251795D01*
Y-252378D01*
X-127089Y-252670D01*
G01X-112646Y-273378D02*
X-111117Y-274545D01*
X-109371Y-274836D01*
X-107843Y-274545D01*
X-106532Y-273087D01*
X-105659Y-271045D01*
Y-257337D01*
G01Y-259670D02*
X-106532Y-258503D01*
X-107843Y-257628D01*
X-109371Y-257337D01*
X-111117Y-257920D01*
X-112209Y-259086D01*
X-113083Y-261128D01*
X-113519Y-263170D01*
X-113301Y-264920D01*
X-112427Y-266962D01*
X-111117Y-268420D01*
X-109371Y-269003D01*
X-108061Y-268711D01*
X-106532Y-267545D01*
X-105659Y-266379D01*
G01X-95801Y-269003D02*
Y-251503D01*
G01Y-259961D02*
X-94709Y-258503D01*
X-93617Y-257628D01*
X-91871Y-257337D01*
X-90561Y-257628D01*
X-89032Y-258795D01*
X-88377Y-260545D01*
Y-269003D01*
G01X-74589Y-251503D02*
Y-269003D01*
G01X-77646Y-257337D02*
X-71532D01*
G01X-60801Y-269003D02*
Y-257337D01*
G01Y-260253D02*
X-59927Y-258795D01*
X-58617Y-257628D01*
X-56871Y-257337D01*
X-55343Y-257628D01*
X-54032Y-258795D01*
X-53377Y-260836D01*
Y-269003D01*
G01X-39589Y-257337D02*
Y-269003D01*
G01Y-252670D02*
X-40026Y-252378D01*
Y-251795D01*
X-39589Y-251503D01*
X-39152Y-251795D01*
Y-252378D01*
X-39589Y-252670D01*
G01X-25801Y-269003D02*
Y-257337D01*
G01Y-260253D02*
X-24927Y-258795D01*
X-23617Y-257628D01*
X-21871Y-257337D01*
X-20343Y-257628D01*
X-19032Y-258795D01*
X-18377Y-260836D01*
Y-269003D01*
G01X-7646Y-273378D02*
X-6117Y-274545D01*
X-4371Y-274836D01*
X-2843Y-274545D01*
X-1532Y-273087D01*
X-659Y-271045D01*
Y-257337D01*
G01Y-259670D02*
X-1532Y-258503D01*
X-2843Y-257628D01*
X-4371Y-257337D01*
X-6117Y-257920D01*
X-7209Y-259086D01*
X-8083Y-261128D01*
X-8519Y-263170D01*
X-8301Y-264920D01*
X-7427Y-266962D01*
X-6117Y-268420D01*
X-4371Y-269003D01*
X-3061Y-268711D01*
X-1532Y-267545D01*
X-659Y-266379D01*
G01X26044Y-269003D02*
Y-251503D01*
X31284D01*
X33031Y-252378D01*
X34341Y-254420D01*
X34778Y-256753D01*
X34341Y-259086D01*
X33249Y-260836D01*
X31284Y-261712D01*
X26044D01*
G01X42452Y-251503D02*
X47911Y-269003D01*
X53370Y-251503D01*
G01X65411D02*
Y-269003D01*
G01X60389Y-251503D02*
X70433D01*
G01X94734Y-269003D02*
Y-251503D01*
X100411Y-266086D01*
X106088Y-251503D01*
Y-269003D01*
G01X117911Y-269586D02*
X117474Y-269295D01*
Y-268711D01*
X117911Y-268420D01*
X118348Y-268711D01*
Y-269295D01*
X117911Y-269586D01*
G01X131263Y-254420D02*
X132573Y-252670D01*
X134101Y-251795D01*
X135848Y-251503D01*
X138031Y-252086D01*
X139559Y-253545D01*
X139996Y-255294D01*
X139778Y-257045D01*
X138904Y-258503D01*
X134538Y-261420D01*
X132573Y-263461D01*
X131263Y-266379D01*
X130826Y-269003D01*
X139996D01*
G01X164952D02*
X170411Y-251503D01*
X175870Y-269003D01*
G01X173904Y-262878D02*
X166917D01*
G01X191841Y-251503D02*
Y-269003D01*
G01Y-266379D02*
X190968Y-267837D01*
X189657Y-268711D01*
X188129Y-269003D01*
X186383Y-268420D01*
X185073Y-266962D01*
X184199Y-265212D01*
X183981Y-263170D01*
X184199Y-261128D01*
X185073Y-259378D01*
X186383Y-257920D01*
X188129Y-257337D01*
X189657Y-257628D01*
X190749Y-258212D01*
X191841Y-259378D01*
G01X209341Y-269003D02*
Y-257337D01*
G01Y-259378D02*
X208468Y-258212D01*
X207157Y-257628D01*
X205629Y-257337D01*
X204101Y-257920D01*
X202791Y-259086D01*
X201917Y-260836D01*
X201481Y-263170D01*
X201917Y-265503D01*
X202791Y-267253D01*
X204101Y-268420D01*
X205629Y-269003D01*
X207157Y-268711D01*
X208468Y-267837D01*
X209341Y-266670D01*
G01X218981Y-274836D02*
Y-257337D01*
G01Y-259961D02*
X220073Y-258503D01*
X221164Y-257628D01*
X222911Y-257337D01*
X224439Y-257628D01*
X225968Y-259086D01*
X226623Y-261128D01*
X226841Y-263170D01*
X226623Y-265212D01*
X225968Y-267253D01*
X224657Y-268420D01*
X222911Y-269003D01*
X221383Y-268711D01*
X219854Y-267837D01*
X218981Y-266670D01*
G01X240411Y-251503D02*
Y-269003D01*
G01X237354Y-257337D02*
X243468D01*
G01X257911Y-269003D02*
X256601Y-268711D01*
X255291Y-267545D01*
X254417Y-265503D01*
X253981Y-263170D01*
X254417Y-260836D01*
X255291Y-258795D01*
X256601Y-257628D01*
X257911Y-257337D01*
X259221Y-257628D01*
X260531Y-258795D01*
X261404Y-260836D01*
X261623Y-263170D01*
X261404Y-265503D01*
X260531Y-267545D01*
X259221Y-268711D01*
X257911Y-269003D01*
G01X272354D02*
Y-257337D01*
G01Y-259670D02*
X273446Y-258503D01*
X274538Y-257628D01*
X276066Y-257337D01*
X277157Y-257628D01*
X278468Y-258503D01*
G01X315214Y-252962D02*
X313904Y-252086D01*
X312376Y-251503D01*
X310629D01*
X308664Y-252378D01*
X307136Y-253836D01*
X306044Y-255587D01*
X305171Y-258503D01*
X304952Y-261128D01*
X305389Y-263753D01*
X306044Y-265503D01*
X307354Y-267253D01*
X308883Y-268420D01*
X310411Y-269003D01*
X311939D01*
X313468Y-268420D01*
X314778Y-267545D01*
X315870Y-266379D01*
G01X331841Y-269003D02*
Y-257337D01*
G01Y-259378D02*
X330968Y-258212D01*
X329657Y-257628D01*
X328129Y-257337D01*
X326601Y-257920D01*
X325291Y-259086D01*
X324417Y-260836D01*
X323981Y-263170D01*
X324417Y-265503D01*
X325291Y-267253D01*
X326601Y-268420D01*
X328129Y-269003D01*
X329657Y-268711D01*
X330968Y-267837D01*
X331841Y-266670D01*
G01X342354Y-269003D02*
Y-257337D01*
G01Y-259670D02*
X343446Y-258503D01*
X344538Y-257628D01*
X346066Y-257337D01*
X347157Y-257628D01*
X348468Y-258503D01*
G01X366841Y-251503D02*
Y-269003D01*
G01Y-266379D02*
X365968Y-267837D01*
X364657Y-268711D01*
X363129Y-269003D01*
X361383Y-268420D01*
X360073Y-266962D01*
X359199Y-265212D01*
X358981Y-263170D01*
X359199Y-261128D01*
X360073Y-259378D01*
X361383Y-257920D01*
X363129Y-257337D01*
X364657Y-257628D01*
X365749Y-258212D01*
X366841Y-259378D01*
G01X68484Y-224003D02*
Y-206503D01*
X74161Y-221086D01*
X79838Y-206503D01*
Y-224003D01*
G01X91661D02*
X90351Y-223711D01*
X89041Y-222545D01*
X88167Y-220503D01*
X87731Y-218170D01*
X88167Y-215836D01*
X89041Y-213795D01*
X90351Y-212628D01*
X91661Y-212337D01*
X92971Y-212628D01*
X94281Y-213795D01*
X95154Y-215836D01*
X95373Y-218170D01*
X95154Y-220503D01*
X94281Y-222545D01*
X92971Y-223711D01*
X91661Y-224003D01*
G01X113091Y-206503D02*
Y-224003D01*
G01Y-221379D02*
X112218Y-222837D01*
X110907Y-223711D01*
X109379Y-224003D01*
X107633Y-223420D01*
X106323Y-221962D01*
X105449Y-220212D01*
X105231Y-218170D01*
X105449Y-216128D01*
X106323Y-214378D01*
X107633Y-212920D01*
X109379Y-212337D01*
X110907Y-212628D01*
X111999Y-213212D01*
X113091Y-214378D01*
G01X123386Y-216128D02*
X130373D01*
X129718Y-214086D01*
X128626Y-212920D01*
X127098Y-212337D01*
X125569Y-212628D01*
X124259Y-213503D01*
X123386Y-215545D01*
X122949Y-217295D01*
Y-219045D01*
X123386Y-220795D01*
X124478Y-222545D01*
X125788Y-223711D01*
X127316Y-224003D01*
X128844Y-223420D01*
X130373Y-221670D01*
G01X144161Y-224003D02*
Y-206503D01*
G01X424761Y-269003D02*
Y-251503D01*
X422141Y-255003D01*
G01Y-269003D02*
X427381D01*
G01X437458Y-266379D02*
X438767Y-267837D01*
X440296Y-268711D01*
X442261Y-269003D01*
X444226Y-268420D01*
X445754Y-267253D01*
X446846Y-265212D01*
X447064Y-262878D01*
X446628Y-260545D01*
X445536Y-259086D01*
X444007Y-257920D01*
X442479Y-257628D01*
X440951Y-257920D01*
X438986Y-259086D01*
X439641Y-251503D01*
X445536D01*
G01X459324Y-269003D02*
X459761Y-265212D01*
X460416Y-262003D01*
X461289Y-259086D01*
X462381Y-255878D01*
X464128Y-251503D01*
X455394D01*
G01X472458Y-266379D02*
X473767Y-267837D01*
X475296Y-268711D01*
X477261Y-269003D01*
X479226Y-268420D01*
X480754Y-267253D01*
X481846Y-265212D01*
X482064Y-262878D01*
X481628Y-260545D01*
X480536Y-259086D01*
X479007Y-257920D01*
X477479Y-257628D01*
X475951Y-257920D01*
X473986Y-259086D01*
X474641Y-251503D01*
X480536D01*
G01X494761D02*
X493014Y-252086D01*
X491704Y-253545D01*
X490831Y-255294D01*
X490176Y-257628D01*
X489958Y-260253D01*
X490176Y-262878D01*
X490831Y-265212D01*
X491704Y-266962D01*
X493014Y-268420D01*
X494761Y-269003D01*
X496507Y-268420D01*
X497818Y-266962D01*
X498691Y-265212D01*
X499346Y-262878D01*
X499564Y-260253D01*
X499346Y-257628D01*
X498691Y-255294D01*
X497818Y-253545D01*
X496507Y-252086D01*
X494761Y-251503D01*
G01X411644Y-224003D02*
Y-206503D01*
X416884D01*
X418631Y-207378D01*
X419941Y-209420D01*
X420378Y-211753D01*
X419941Y-214086D01*
X418849Y-215836D01*
X416884Y-216712D01*
X411644D01*
G01X438314Y-207962D02*
X437004Y-207086D01*
X435476Y-206503D01*
X433729D01*
X431764Y-207378D01*
X430236Y-208836D01*
X429144Y-210587D01*
X428271Y-213503D01*
X428052Y-216128D01*
X428489Y-218753D01*
X429144Y-220503D01*
X430454Y-222253D01*
X431983Y-223420D01*
X433511Y-224003D01*
X435039D01*
X436568Y-223420D01*
X437878Y-222545D01*
X438970Y-221379D01*
G01X452757Y-214670D02*
X453631Y-213795D01*
X454286Y-212337D01*
X454723Y-210294D01*
X454286Y-208545D01*
X453413Y-207378D01*
X451884Y-206503D01*
X445989D01*
Y-224003D01*
X453194D01*
X454723Y-222837D01*
X455596Y-221086D01*
X456033Y-219045D01*
X455596Y-217003D01*
X454286Y-215253D01*
X452757Y-214670D01*
X445989D01*
G01X461961Y-229836D02*
X475061D01*
G01X480989Y-224003D02*
Y-206503D01*
X491033Y-224003D01*
Y-206503D01*
G01X503511Y-224003D02*
X501764Y-223711D01*
X500236Y-222545D01*
X498926Y-220795D01*
X498052Y-218753D01*
X497616Y-216420D01*
Y-214086D01*
X498052Y-211753D01*
X498926Y-209711D01*
X500236Y-207962D01*
X501764Y-206795D01*
X503511Y-206503D01*
X505257Y-206795D01*
X506786Y-207962D01*
X508096Y-209711D01*
X508970Y-211753D01*
X509406Y-214086D01*
Y-216420D01*
X508970Y-218753D01*
X508096Y-220795D01*
X506786Y-222545D01*
X505257Y-223711D01*
X503511Y-224003D01*
G01X554352Y-206503D02*
X559811Y-224003D01*
X565270Y-206503D01*
G01X581678Y-224003D02*
X572944D01*
Y-206503D01*
X581678D01*
G01X578184Y-214961D02*
X572944D01*
G01X590444Y-224003D02*
Y-206503D01*
X595903D01*
X597649Y-207378D01*
X598741Y-208545D01*
X599178Y-210878D01*
X598741Y-213212D01*
X597431Y-214670D01*
X595903Y-215545D01*
X590444D01*
G01X595903D02*
X599178Y-224003D01*
G01X612311Y-224586D02*
X611874Y-224295D01*
Y-223711D01*
X612311Y-223420D01*
X612748Y-223711D01*
Y-224295D01*
X612311Y-224586D01*
G01X586061Y-269003D02*
Y-251503D01*
X583441Y-255003D01*
G01Y-269003D02*
X588681D01*
G01X687894Y-206503D02*
Y-224003D01*
X696628D01*
G01X713691D02*
Y-212337D01*
G01Y-214378D02*
X712818Y-213212D01*
X711507Y-212628D01*
X709979Y-212337D01*
X708451Y-212920D01*
X707141Y-214086D01*
X706267Y-215836D01*
X705831Y-218170D01*
X706267Y-220503D01*
X707141Y-222253D01*
X708451Y-223420D01*
X709979Y-224003D01*
X711507Y-223711D01*
X712818Y-222837D01*
X713691Y-221670D01*
G01X722676Y-229253D02*
X723986Y-229836D01*
X725733Y-229253D01*
X726824Y-228087D01*
X727698Y-226628D01*
X729007Y-221962D01*
X731846Y-212337D01*
G01X724859D02*
X729007Y-221962D01*
G01X741486Y-216128D02*
X748473D01*
X747818Y-214086D01*
X746726Y-212920D01*
X745198Y-212337D01*
X743669Y-212628D01*
X742359Y-213503D01*
X741486Y-215545D01*
X741049Y-217295D01*
Y-219045D01*
X741486Y-220795D01*
X742578Y-222545D01*
X743888Y-223711D01*
X745416Y-224003D01*
X746944Y-223420D01*
X748473Y-221670D01*
G01X759204Y-224003D02*
Y-212337D01*
G01Y-214670D02*
X760296Y-213503D01*
X761388Y-212628D01*
X762916Y-212337D01*
X764007Y-212628D01*
X765318Y-213503D01*
G01X714144Y-251503D02*
Y-269003D01*
X722878D01*
G01X736011D02*
Y-251503D01*
X733391Y-255003D01*
G01Y-269003D02*
X738631D01*
G01X830008Y-224003D02*
Y-206503D01*
X834374D01*
X836121Y-207378D01*
X837431Y-208545D01*
X838523Y-210294D01*
X839396Y-212337D01*
X839614Y-215253D01*
X839396Y-218170D01*
X838523Y-220212D01*
X837431Y-221962D01*
X836121Y-223128D01*
X834374Y-224003D01*
X830008D01*
G01X849036Y-216128D02*
X856023D01*
X855368Y-214086D01*
X854276Y-212920D01*
X852748Y-212337D01*
X851219Y-212628D01*
X849909Y-213503D01*
X849036Y-215545D01*
X848599Y-217295D01*
Y-219045D01*
X849036Y-220795D01*
X850128Y-222545D01*
X851438Y-223711D01*
X852966Y-224003D01*
X854494Y-223420D01*
X856023Y-221670D01*
G01X866536Y-221962D02*
X867628Y-223128D01*
X869156Y-224003D01*
X870466D01*
X871776Y-223420D01*
X872649Y-222545D01*
X873086Y-221379D01*
X872868Y-219628D01*
X871994Y-218753D01*
X868064Y-217003D01*
X867191Y-214961D01*
X867628Y-213503D01*
X868501Y-212628D01*
X869811Y-212337D01*
X871121Y-212628D01*
X872431Y-213503D01*
G01X887311Y-212337D02*
Y-224003D01*
G01Y-207670D02*
X886874Y-207378D01*
Y-206795D01*
X887311Y-206503D01*
X887748Y-206795D01*
Y-207378D01*
X887311Y-207670D01*
G01X901754Y-228378D02*
X903283Y-229545D01*
X905029Y-229836D01*
X906557Y-229545D01*
X907868Y-228087D01*
X908741Y-226045D01*
Y-212337D01*
G01Y-214670D02*
X907868Y-213503D01*
X906557Y-212628D01*
X905029Y-212337D01*
X903283Y-212920D01*
X902191Y-214086D01*
X901317Y-216128D01*
X900881Y-218170D01*
X901099Y-219920D01*
X901973Y-221962D01*
X903283Y-223420D01*
X905029Y-224003D01*
X906339Y-223711D01*
X907868Y-222545D01*
X908741Y-221379D01*
G01X918599Y-224003D02*
Y-212337D01*
G01Y-215253D02*
X919473Y-213795D01*
X920783Y-212628D01*
X922529Y-212337D01*
X924057Y-212628D01*
X925368Y-213795D01*
X926023Y-215836D01*
Y-224003D01*
G01X936536Y-216128D02*
X943523D01*
X942868Y-214086D01*
X941776Y-212920D01*
X940248Y-212337D01*
X938719Y-212628D01*
X937409Y-213503D01*
X936536Y-215545D01*
X936099Y-217295D01*
Y-219045D01*
X936536Y-220795D01*
X937628Y-222545D01*
X938938Y-223711D01*
X940466Y-224003D01*
X941994Y-223420D01*
X943523Y-221670D01*
G01X954254Y-224003D02*
Y-212337D01*
G01Y-214670D02*
X955346Y-213503D01*
X956438Y-212628D01*
X957966Y-212337D01*
X959057Y-212628D01*
X960368Y-213503D01*
G01X874194Y-265503D02*
X875286Y-267253D01*
X876596Y-268420D01*
X878124Y-269003D01*
X879871Y-268420D01*
X881181Y-267253D01*
X882491Y-265503D01*
X882928Y-263170D01*
Y-251503D01*
G01X896061Y-269003D02*
X894314Y-268711D01*
X892786Y-267545D01*
X891476Y-265795D01*
X890602Y-263753D01*
X890166Y-261420D01*
Y-259086D01*
X890602Y-256753D01*
X891476Y-254711D01*
X892786Y-252962D01*
X894314Y-251795D01*
X896061Y-251503D01*
X897807Y-251795D01*
X899336Y-252962D01*
X900646Y-254711D01*
X901520Y-256753D01*
X901956Y-259086D01*
Y-261420D01*
X901520Y-263753D01*
X900646Y-265795D01*
X899336Y-267545D01*
X897807Y-268711D01*
X896061Y-269003D01*
G01X913561D02*
Y-261128D01*
X909194Y-251503D01*
G01X917928D02*
X913561Y-261128D01*
G01X1001011Y-269003D02*
Y-251503D01*
X998391Y-255003D01*
G01Y-269003D02*
X1003631D01*
G01X1014363Y-254420D02*
X1015673Y-252670D01*
X1017201Y-251795D01*
X1018948Y-251503D01*
X1021131Y-252086D01*
X1022659Y-253545D01*
X1023096Y-255294D01*
X1022878Y-257045D01*
X1022004Y-258503D01*
X1017638Y-261420D01*
X1015673Y-263461D01*
X1014363Y-266379D01*
X1013926Y-269003D01*
X1023096D01*
G01X1032081Y-269586D02*
X1039941Y-251503D01*
G01X1048708Y-265503D02*
X1050017Y-267545D01*
X1051764Y-268711D01*
X1053729Y-269003D01*
X1055476Y-268711D01*
X1057223Y-267253D01*
X1058314Y-265503D01*
X1058533Y-263753D01*
X1058096Y-261712D01*
X1056568Y-260253D01*
X1055039Y-259670D01*
X1053074D01*
G01X1055039D02*
X1056349Y-258795D01*
X1057441Y-257337D01*
X1057878Y-255587D01*
X1057441Y-253836D01*
X1056349Y-252378D01*
X1054384Y-251503D01*
X1052419Y-251795D01*
X1050454Y-252962D01*
G01X1071011Y-251503D02*
X1069264Y-252086D01*
X1067954Y-253545D01*
X1067081Y-255294D01*
X1066426Y-257628D01*
X1066208Y-260253D01*
X1066426Y-262878D01*
X1067081Y-265212D01*
X1067954Y-266962D01*
X1069264Y-268420D01*
X1071011Y-269003D01*
X1072757Y-268420D01*
X1074068Y-266962D01*
X1074941Y-265212D01*
X1075596Y-262878D01*
X1075814Y-260253D01*
X1075596Y-257628D01*
X1074941Y-255294D01*
X1074068Y-253545D01*
X1072757Y-252086D01*
X1071011Y-251503D01*
G01X1084581Y-269586D02*
X1092441Y-251503D01*
G01X1101863Y-254420D02*
X1103173Y-252670D01*
X1104701Y-251795D01*
X1106448Y-251503D01*
X1108631Y-252086D01*
X1110159Y-253545D01*
X1110596Y-255294D01*
X1110378Y-257045D01*
X1109504Y-258503D01*
X1105138Y-261420D01*
X1103173Y-263461D01*
X1101863Y-266379D01*
X1101426Y-269003D01*
X1110596D01*
G01X1123511Y-251503D02*
X1121764Y-252086D01*
X1120454Y-253545D01*
X1119581Y-255294D01*
X1118926Y-257628D01*
X1118708Y-260253D01*
X1118926Y-262878D01*
X1119581Y-265212D01*
X1120454Y-266962D01*
X1121764Y-268420D01*
X1123511Y-269003D01*
X1125257Y-268420D01*
X1126568Y-266962D01*
X1127441Y-265212D01*
X1128096Y-262878D01*
X1128314Y-260253D01*
X1128096Y-257628D01*
X1127441Y-255294D01*
X1126568Y-253545D01*
X1125257Y-252086D01*
X1123511Y-251503D01*
G01X1141011Y-269003D02*
Y-251503D01*
X1138391Y-255003D01*
G01Y-269003D02*
X1143631D01*
G01X1154363Y-261712D02*
X1155891Y-259670D01*
X1157201Y-258503D01*
X1158948Y-257920D01*
X1160476Y-258503D01*
X1161568Y-259670D01*
X1162441Y-261420D01*
X1162659Y-263461D01*
X1162441Y-265212D01*
X1161568Y-266962D01*
X1160257Y-268420D01*
X1158729Y-269003D01*
X1156983Y-268420D01*
X1155454Y-266670D01*
X1154581Y-264045D01*
X1154363Y-261128D01*
X1154799Y-257337D01*
X1155454Y-255294D01*
X1156546Y-253253D01*
X1158074Y-251795D01*
X1159603Y-251503D01*
X1161131Y-252086D01*
X1162223Y-253545D01*
G01X1048708Y-224003D02*
Y-206503D01*
X1053074D01*
X1054821Y-207378D01*
X1056131Y-208545D01*
X1057223Y-210294D01*
X1058096Y-212337D01*
X1058314Y-215253D01*
X1058096Y-218170D01*
X1057223Y-220212D01*
X1056131Y-221962D01*
X1054821Y-223128D01*
X1053074Y-224003D01*
X1048708D01*
G01X1074941D02*
Y-212337D01*
G01Y-214378D02*
X1074068Y-213212D01*
X1072757Y-212628D01*
X1071229Y-212337D01*
X1069701Y-212920D01*
X1068391Y-214086D01*
X1067517Y-215836D01*
X1067081Y-218170D01*
X1067517Y-220503D01*
X1068391Y-222253D01*
X1069701Y-223420D01*
X1071229Y-224003D01*
X1072757Y-223711D01*
X1074068Y-222837D01*
X1074941Y-221670D01*
G01X1088511Y-206503D02*
Y-224003D01*
G01X1085454Y-212337D02*
X1091568D01*
G01X1102736Y-216128D02*
X1109723D01*
X1109068Y-214086D01*
X1107976Y-212920D01*
X1106448Y-212337D01*
X1104919Y-212628D01*
X1103609Y-213503D01*
X1102736Y-215545D01*
X1102299Y-217295D01*
Y-219045D01*
X1102736Y-220795D01*
X1103828Y-222545D01*
X1105138Y-223711D01*
X1106666Y-224003D01*
X1108194Y-223420D01*
X1109723Y-221670D01*
G54D15*
X56200Y325189D03*
X67200Y302689D03*
X207300Y300200D03*
X233700Y67000D03*
Y75000D03*
Y71000D03*
Y122000D03*
Y126000D03*
Y138500D03*
Y130000D03*
Y134500D03*
Y175500D03*
Y183500D03*
Y179500D03*
Y238500D03*
Y243000D03*
Y230500D03*
Y234500D03*
Y247000D03*
G54D51*
X249000Y315100D03*
Y339900D03*
G54D33*
X100200Y310000D03*
G54D24*
X71500Y315689D03*
G54D42*
X176311Y301700D03*
X294000Y154200D03*
X298000D03*
G54D61*
G01X286319Y87362D02*
X289495D01*
G03X289848Y87508I0J500D01*
G01X289961Y87621D01*
G02X290314Y87767I353J-354D01*
G01X291400D01*
G02X295000Y86699I0J-6601D01*
G01X286319Y89330D02*
X289523D01*
G02X289876Y89184I0J-500D01*
G01X289989Y89071D01*
G03X290342Y88925I353J354D01*
G01X290700D01*
G03X295000Y89899I0J9979D01*
G01X325244Y68799D02*
X325201Y68842D01*
G03X322900Y69795I-2301J-2301D01*
G01X320983D01*
G02X318396Y70866I0J3660D01*
G01X296998Y92264D01*
G03X293596Y93673I-3402J-3402D01*
G01X290387D01*
G03X289897Y93470I0J-693D01*
G02X289407Y93267I-490J490D01*
G01X286319D01*
G01X325244Y71949D02*
X325201Y71906D01*
G02X322900Y70953I-2301J2301D01*
G01X320983D01*
G02X319215Y71685I0J2501D01*
G01X311450Y79450D01*
X297818Y93083D01*
X297817D01*
G03X293596Y94831I-4220J-4221D01*
G01X290415D01*
G02X289926Y95033I0J692D01*
G01X289882Y95077D01*
G03X289500Y95236I-382J-379D01*
G01X286319D01*
G01X325244Y87697D02*
X324777Y88164D01*
G03X323500Y88693I-1277J-1277D01*
G02X321058Y89704I0J3455D01*
G01X315631Y95131D01*
X308234Y102527D01*
G03X301095Y105484I-7139J-7139D01*
G01X290387D01*
G03X289897Y105281I0J-693D01*
G02X289407Y105078I-490J490D01*
G01X286319D01*
G01X325244Y90847D02*
X324777Y90380D01*
G02X323500Y89851I-1277J1277D01*
G02X321877Y90523I0J2296D01*
G01X309054Y103346D01*
X309053D01*
G03X301095Y106642I-7958J-7958D01*
G01X290386D01*
G02X289898Y106844I0J690D01*
G03X289408Y107047I-490J-490D01*
G01X286319D01*
G01Y110984D02*
X282307D01*
G02X281954Y111130I0J500D01*
G01X281841Y111243D01*
G03X281488Y111389I-353J-354D01*
G01X277500D01*
G03X276269Y110879I0J-1741D01*
G01X275100Y109710D01*
G01X286319Y101141D02*
X282349D01*
G03X281996Y100995I0J-500D01*
G01X281883Y100882D01*
G02X281530Y100736I-353J354D01*
G01X275500D01*
G02X274071Y101328I0J2021D01*
G01X273100Y102299D01*
G01X286319Y99173D02*
X282433D01*
G02X282080Y99319I0J500D01*
G01X281967Y99432D01*
G03X281614Y99578I-353J-354D01*
G01X275500D01*
G03X274269Y99068I0J-1741D01*
G01X273100Y97899D01*
G01X286319Y112952D02*
X282460D01*
G03X282107Y112806I0J-500D01*
G01X281994Y112693D01*
G02X281641Y112547I-353J354D01*
G01X277500D01*
G02X276071Y113139I0J2021D01*
G01X275100Y114110D01*
G01X291300Y198561D02*
G02X289500Y197992I-1800J2563D01*
G01X286319D01*
G01X291300Y195361D02*
G03X289699Y196024I-1601J-1602D01*
G01X286319D01*
G01X325244Y106595D02*
X324777Y107062D01*
G03X323500Y107591I-1277J-1277D01*
G01X322287D01*
G02X319700Y108662I0J3660D01*
G01X316937Y111425D01*
G02X314526Y115023I7889J7893D01*
G01X310199Y125408D01*
G02X309342Y129700I10302J4289D01*
G01Y167964D01*
G03X308949Y168913I-1342J0D01*
G01X300513Y177349D01*
G02X299442Y179936I2589J2587D01*
G01Y198522D01*
G03X295629Y202335I-3813J0D01*
G01X290387D01*
G03X289897Y202132I0J-693D01*
G02X289407Y201929I-490J490D01*
G01X286319D01*
G01X325244Y109744D02*
X324778Y109279D01*
G02X323500Y108749I-1279J1278D01*
G01X322287D01*
G02X320519Y109481I0J2501D01*
G01X317756Y112244D01*
G02X315596Y115469I7071J7072D01*
G01X311269Y125854D01*
G02X310500Y129700I9231J3846D01*
G01Y167964D01*
G03X309768Y169732I-2501J0D01*
G01X301332Y178168D01*
G02X300600Y179936I1769J1768D01*
G01Y198522D01*
G03X295629Y203493I-4971J0D01*
G01X290415D01*
G02X289926Y203695I0J692D01*
G01X289882Y203739D01*
G03X289500Y203898I-382J-379D01*
G01X286319D01*
G01Y209803D02*
X282349D01*
G03X281996Y209657I0J-500D01*
G01X281883Y209544D01*
G02X281530Y209398I-353J354D01*
G01X275500D01*
G02X274071Y209990I0J2021D01*
G01X273100Y210961D01*
G01X286319Y207835D02*
X282433D01*
G02X282080Y207981I0J500D01*
G01X281967Y208094D01*
G03X281614Y208240I-353J-354D01*
G01X275500D01*
G03X274269Y207730I0J-1741D01*
G01X273100Y206561D01*
G01X325244Y156988D02*
G03X322839Y157984I-2405J-2405D01*
G01X322394D01*
G02X319807Y159055I0J3660D01*
G01X316682Y162180D01*
G02X315611Y164767I2589J2587D01*
G01Y167853D01*
G03X314879Y169621I-2501J0D01*
G01X304674Y179826D01*
G02X303942Y181594I1769J1768D01*
G01Y191406D01*
G02X304674Y193174I2501J0D01*
G01X312610Y201110D01*
G03X313342Y202878I-1769J1768D01*
G01Y214122D01*
G03X312610Y215890I-2501J0D01*
G01X312390Y216110D01*
G03X310622Y216842I-1768J-1769D01*
G01X299036D01*
G03X298087Y216449I0J-1342D01*
G01X296855Y215217D01*
G02X294268Y214146I-2587J2589D01*
G01X290387D01*
G03X289897Y213943I0J-693D01*
G02X289407Y213740I-490J490D01*
G01X286319D01*
G01X325244Y160138D02*
G02X322839Y159142I-2405J2405D01*
G01X322394D01*
G02X320626Y159874I0J2501D01*
G01X317501Y162999D01*
G02X316769Y164767I1769J1768D01*
G01Y167853D01*
G03X315698Y170440I-3660J0D01*
G01X305493Y180645D01*
G02X305100Y181594I949J949D01*
G01Y191406D01*
G02X305493Y192355I1342J0D01*
G01X313429Y200291D01*
G03X314500Y202878I-2589J2587D01*
G01Y214122D01*
G03X313429Y216709I-3660J0D01*
G01X313209Y216929D01*
G03X310622Y218000I-2587J-2589D01*
G01X299036D01*
G03X297268Y217268I0J-2501D01*
G01X296036Y216036D01*
G02X294268Y215304I-1768J1769D01*
G01X290415D01*
G02X289926Y215506I0J692D01*
G01X289882Y215550D01*
G03X289500Y215709I-382J-379D01*
G01X286319D01*
G01Y221614D02*
X282460D01*
G03X282107Y221468I0J-500D01*
G01X281994Y221355D01*
G02X281641Y221209I-353J354D01*
G01X277500D01*
G02X276071Y221801I0J2021D01*
G01X275100Y222772D01*
G01X286319Y219646D02*
X282307D01*
G02X281954Y219792I0J500D01*
G01X281841Y219905D01*
G03X281488Y220051I-353J-354D01*
G01X277500D01*
G03X276269Y219541I0J-1741D01*
G01X275100Y218372D01*
G54D25*
X58000Y320489D03*
X169500Y336300D03*
X196000Y341300D03*
G54D43*
X176311Y298300D03*
X294000Y150800D03*
X298000D03*
G54D34*
X103800Y310000D03*
G54D16*
X53500Y320689D03*
X71000Y294189D03*
X66750Y289689D03*
X59000Y304189D03*
X68000Y339189D03*
X58000Y337439D03*
X77500Y338000D03*
X95000Y289000D03*
X94500Y303100D03*
X96500Y332500D03*
X117913Y287300D03*
X122500Y285500D03*
X110500Y306000D03*
X123500Y304700D03*
X128500Y304500D03*
X162311Y298500D03*
X194811Y303500D03*
X207500Y296250D03*
X258000Y160500D03*
X299500Y144900D03*
X298500Y254000D03*
G54D52*
X283268Y63346D03*
Y144842D03*
Y172008D03*
Y253504D03*
G54D62*
G01X95000Y277500D02*
X99962Y272538D01*
X105874D01*
X107300Y271112D01*
X116112D01*
X121500Y276500D01*
G01X95000Y280750D02*
Y277500D01*
G01X118000Y276500D02*
X114587Y273087D01*
X108119D01*
X106693Y274513D01*
X101987D01*
X99000Y277500D01*
G01Y280750D02*
Y277500D01*
G01X101015Y293900D02*
Y289515D01*
X100000Y288500D01*
G01X95000Y284250D02*
X92162Y287088D01*
Y290175D01*
X95000Y293013D01*
Y299448D01*
X94500Y299948D01*
Y303100D01*
G01X110500Y306000D02*
Y302152D01*
X109010Y300662D01*
X107162D01*
X104955Y298455D01*
Y293900D01*
G01X99000Y284250D02*
X95000Y288250D01*
Y289000D01*
G01D02*
Y289855D01*
X99045Y293900D01*
G01X108000Y303100D02*
X104955D01*
G01X99045D02*
X94500D01*
G01X100250Y317000D02*
X103500D01*
G01X107325Y320089D02*
X106589D01*
X103500Y317000D01*
G01X109880Y320089D02*
Y322277D01*
X108330Y323827D01*
X106320D01*
X105887Y323394D01*
Y323387D01*
X103500Y321000D01*
G01X100250D02*
X103500D01*
G01X100250Y325000D02*
X101052Y325802D01*
X109149D01*
X112440Y322511D01*
Y320089D01*
G01X100250Y325000D02*
Y328750D01*
X96500Y332500D01*
G01X106500Y277500D02*
X109512Y280512D01*
X110635D01*
X111873Y281750D01*
X114500D01*
G01X106500Y277500D02*
X108938Y275062D01*
X113062D01*
X114500Y276500D01*
G01X110500Y277500D02*
X112438Y279438D01*
X118188D01*
X119000Y280250D01*
G01X117913Y287300D02*
Y288032D01*
X113900Y292045D01*
G01X114500Y285250D02*
X115863D01*
X117913Y287300D01*
G01X122500Y285500D02*
X120750Y283750D01*
X119000D01*
G01Y308250D02*
Y305000D01*
G01X115000Y308250D02*
X112750D01*
X110500Y306000D01*
G01X123500Y304700D02*
X122024Y303224D01*
X121320D01*
X116051Y297955D01*
X113900D01*
G01X120120Y320089D02*
Y315000D01*
G01X119000Y311750D02*
Y313880D01*
X120120Y315000D01*
G01X117560Y320089D02*
Y316060D01*
X116500Y315000D01*
G01X115000Y311750D02*
Y313500D01*
X116500Y315000D01*
G01X109880Y342289D02*
Y334880D01*
X109500Y334500D01*
G01X112440Y342289D02*
Y335060D01*
X113000Y334500D01*
G01X117000D02*
X126438Y325062D01*
Y313990D01*
X125010Y312562D01*
X124312D01*
X123500Y311750D01*
G01X117560Y342289D02*
Y335060D01*
X117000Y334500D01*
G01X121000D02*
X120120Y335380D01*
Y342289D01*
G01X121000Y334500D02*
X128413Y327087D01*
Y312663D01*
X127500Y311750D01*
G01X126000Y287000D02*
X126838Y287838D01*
Y292950D01*
X125773Y294015D01*
X123100D01*
G01X122500Y285500D02*
X123562Y286562D01*
Y291583D01*
X123100Y292045D01*
G01X123500Y304700D02*
Y308250D01*
G01X128500Y304500D02*
Y307250D01*
X127500Y308250D01*
G01X123100Y297955D02*
Y299100D01*
X128500Y304500D01*
G01X230410Y157220D02*
X235780D01*
X237000Y156000D01*
G01X230410Y159780D02*
X237000D01*
G01X236500Y168500D02*
X231410D01*
X230410Y167500D01*
Y162340D01*
G01X252000Y151500D02*
X248840Y154660D01*
X246590D01*
G01X252000Y155000D02*
X249780Y157220D01*
X246590D01*
G01Y159780D02*
X251280D01*
X252000Y160500D01*
G01D02*
X258000D01*
G01X256594Y200945D02*
X263000D01*
X270500Y193445D01*
Y167454D01*
X265702Y162656D01*
Y159786D01*
X270138Y155350D01*
Y141138D01*
X267528Y138528D01*
Y96593D01*
X268660Y95461D01*
X269822D01*
X273000Y92283D01*
G01X256594D02*
X273000D01*
G01X256594Y90314D02*
X261186D01*
X263000Y88500D01*
G01X256594Y84409D02*
X259665Y81338D01*
X263000D01*
G01X256594Y86377D02*
X261461D01*
X263000Y84838D01*
G01Y96500D02*
X261312Y98188D01*
X256594D01*
G01Y102125D02*
X261125D01*
X263000Y104000D01*
G01X256594Y100157D02*
X262819D01*
G01X256594Y131653D02*
X262920D01*
G01X256594Y193071D02*
X259665Y190000D01*
X263000D01*
G01X256594Y195039D02*
X261461D01*
X263000Y193500D01*
G01X256594Y206850D02*
X261150D01*
X263000Y205000D01*
G01X256594Y198976D02*
X261024D01*
X263000Y197000D01*
G01Y212500D02*
X261287Y210787D01*
X256594D01*
G01X302000Y290500D02*
X300275Y288775D01*
Y283881D01*
X296847Y280453D01*
X285047D01*
X272975Y268381D01*
Y249081D01*
X270675Y246781D01*
Y240181D01*
X265475Y234981D01*
Y211527D01*
X262819Y208871D01*
Y208819D01*
G01X256594D02*
X262819D01*
G01X302000Y300500D02*
X298300Y296800D01*
Y284700D01*
X296028Y282428D01*
X284228D01*
X270999Y269199D01*
Y267563D01*
X271000Y267562D01*
Y249900D01*
X268700Y247600D01*
Y241000D01*
X263500Y235800D01*
Y213000D01*
X263000Y212500D01*
G01X256594Y240315D02*
X263000D01*
G01X286319Y140511D02*
X293261D01*
X296000Y143250D01*
G01X294750Y249000D02*
X290961D01*
X290788Y249173D01*
X286319D01*
G01X325244Y49902D02*
X307598D01*
X296500Y61000D01*
G01X300500D02*
Y59794D01*
X308417Y51877D01*
X324070D01*
X325244Y53051D01*
G01X304500Y123820D02*
Y119000D01*
X295500Y110000D01*
G01X296000Y135750D02*
X293750D01*
X293000Y135000D01*
Y129911D01*
X295311Y127600D01*
G01X296000Y139750D02*
Y135750D01*
G01X299500Y144900D02*
X297650D01*
X296000Y143250D01*
G01X290500Y154250D02*
X294000D01*
G01X295440Y162250D02*
X294000Y160810D01*
Y154250D01*
G01X298000Y162250D02*
Y159000D01*
X296500Y157500D01*
G01X298000Y154250D02*
X296500Y155750D01*
Y157500D01*
G01X300560Y168750D02*
X297422Y171888D01*
X293388D01*
X291000Y169500D01*
G01X298250Y249000D02*
Y245000D01*
G01D02*
X301711D01*
G01X294750Y249000D02*
Y250250D01*
X298500Y254000D01*
G54D35*
X100200Y317000D03*
Y321000D03*
X298200Y249000D03*
G54D17*
X58200Y331189D03*
X65800D03*
X76700Y285689D03*
X84300D03*
X76700Y293689D03*
X84300D03*
X76700Y301689D03*
X84300D03*
X76700Y331189D03*
X84300D03*
X255200Y296000D03*
Y304000D03*
X262800Y296000D03*
Y304000D03*
G54D44*
X185811Y298250D03*
G54D53*
X297000Y118200D03*
G54D26*
X58000Y314889D03*
X169500Y330700D03*
X196000Y335700D03*
G54D36*
X96800Y317000D03*
Y321000D03*
X294800Y249000D03*
G54D45*
X185811Y300750D03*
G54D27*
X62000Y337489D03*
X95000Y280800D03*
X99000D03*
X114500Y281800D03*
X119000Y280300D03*
Y308300D03*
X115000D03*
X123500D03*
X127500D03*
X168311Y298300D03*
X199811Y296300D03*
X296000Y132300D03*
Y139800D03*
G54D54*
X297000Y123800D03*
G54D18*
X63300Y294189D03*
X67300Y298689D03*
X70800Y345000D03*
X96800Y325000D03*
X192111Y299500D03*
X204111Y304000D03*
X294800Y245000D03*
G54D28*
X62000Y340889D03*
X95000Y284200D03*
X99000D03*
X114500Y285200D03*
X119000Y283700D03*
Y311700D03*
X115000D03*
X123500D03*
X127500D03*
X168311Y301700D03*
X199811Y299700D03*
X296000Y135700D03*
Y143200D03*
G54D55*
X295440Y162250D03*
X298000D03*
X300560D03*
Y168750D03*
X295440D03*
G54D37*
X123100Y294015D03*
Y292045D03*
X113900D03*
Y294015D03*
X123100Y297955D03*
Y295985D03*
X113900D03*
Y297955D03*
G54D19*
X66700Y294189D03*
X70700Y298689D03*
X74200Y345000D03*
X100200Y325000D03*
X195511Y299500D03*
X207511Y304000D03*
X298200Y245000D03*
G54D46*
X206943Y324000D03*
X232057D03*
G54D29*
X71500Y329389D03*
X165000Y308200D03*
X249000Y144200D03*
Y252700D03*
G54D47*
X208200Y292000D03*
G54D38*
X107325Y320089D03*
X109880D03*
X112440D03*
X115000D03*
X117560D03*
X120120D03*
X122675D03*
Y342289D03*
X120120D03*
X117560D03*
X115000D03*
X112440D03*
X109880D03*
X107325D03*
G54D56*
X302000Y290500D03*
Y300500D03*
Y310500D03*
G54D57*
G01X67565Y309589D02*
X64500D01*
G01X65800Y331189D02*
Y327510D01*
X69530Y323780D01*
Y321789D01*
G01X103000Y284250D02*
X102985Y284265D01*
Y293900D01*
G01Y303100D02*
Y306650D01*
X103715Y307380D01*
Y309965D01*
X103750Y310000D01*
G01X101015Y303100D02*
Y306735D01*
X100250Y307500D01*
Y310000D01*
G01X107325Y342289D02*
X100650D01*
X100500Y342439D01*
G01X109500Y286750D02*
Y293000D01*
X110515Y294015D01*
X113900D01*
G01Y295985D02*
X117086D01*
X118000Y296899D01*
Y298011D01*
X120989Y301000D01*
X122000D01*
G01X123100Y295985D02*
X126286D01*
X127021Y295250D01*
X130000D01*
G01X176168Y314563D02*
X170874D01*
X169811Y313500D01*
G01X176168Y316531D02*
X168531D01*
X165000Y313000D01*
Y311750D01*
G01X195454Y314563D02*
X200248D01*
X200811Y314000D01*
G01X230410Y154660D02*
X232840D01*
X235000Y152500D01*
X237000D01*
G01X286319Y71614D02*
X280000D01*
G01X286319Y91299D02*
X291550D01*
G01X286319Y85393D02*
X291500D01*
G01X286319Y109015D02*
X290555D01*
X291500Y109960D01*
G01X286319Y97204D02*
X291500D01*
G01X286319Y103110D02*
X290350D01*
X291500Y101960D01*
G01X286319Y126732D02*
X280169D01*
G01X286319Y120826D02*
X280169D01*
G01X286319Y114921D02*
X291500D01*
G01X286319Y138543D02*
X280169D01*
G01X286319Y132637D02*
X280169D01*
G01X280000Y176339D02*
X286319D01*
G01Y178307D02*
X281185D01*
G01X286319Y180276D02*
X280000D01*
G01X286319Y194055D02*
X273500D01*
G01X286319Y199961D02*
X273500D01*
G01X286319Y211772D02*
X290689D01*
X291500Y210961D01*
G01X286319Y205866D02*
X291500D01*
G01X286319Y217677D02*
X290716D01*
X291500Y218461D01*
G01X286319Y223583D02*
X291500D01*
G01X286319Y241299D02*
X291500D01*
G01X286319Y229488D02*
X291500D01*
G01X286319Y235394D02*
X291500D01*
G01X280169Y247205D02*
X286319D01*
G54D39*
X139000Y312200D03*
Y319800D03*
Y329200D03*
Y336800D03*
X147000Y312200D03*
X155000D03*
X147000Y319800D03*
X155000D03*
Y329200D03*
Y336800D03*
X147000Y329200D03*
Y336800D03*
X163000Y329200D03*
Y336800D03*
X189500Y336200D03*
Y343800D03*
G54D48*
X213800Y292000D03*
G54D58*
G01X122675Y320089D02*
Y316547D01*
X123020Y316202D01*
Y315980D01*
X124000Y315000D01*
G01X251500Y164500D02*
X249340Y162340D01*
X246590D01*
G54D49*
X230410Y154660D03*
Y157220D03*
Y159780D03*
Y162340D03*
X246590D03*
Y159780D03*
Y157220D03*
Y154660D03*
G54D59*
G01X300560Y162250D02*
Y158940D01*
X302000Y157500D01*
G01X295440Y168750D02*
Y168690D01*
X290000Y163250D01*
M02*
